G04 ================== begin FILE IDENTIFICATION RECORD ==================*
G04 Layout Name:  12433-2a.brd*
G04 Film Name:    L3VCC*
G04 File Format:  Gerber RS274X*
G04 File Origin:  Cadence Allegro 16.5-S056*
G04 Origin Date:  Fri Dec 11 16:47:41 2015*
G04 *
G04 Layer:  VIA CLASS/L3VCC*
G04 Layer:  PIN/L3VCC*
G04 Layer:  PACKAGE GEOMETRY/PWRVCC*
G04 Layer:  ETCH/L3VCC*
G04 Layer:  DRAWING FORMAT/LAYER_PCB_STORY*
G04 Layer:  DRAWING FORMAT/LAYER_L3VCC*
G04 *
G04 Offset:    (0.00 0.00)*
G04 Mirror:    No*
G04 Mode:      Negative*
G04 Rotation:  0*
G04 FullContactRelief:  No*
G04 UndefLineWidth:     6.00*
G04 ================== end FILE IDENTIFICATION RECORD ====================*
%FSLAX35Y35*MOIN*%
%IR0*IPPOS*OFA0.00000B0.00000*MIA0B0*SFA1.00000B1.00000*%
%AMMACRO26*
4,1,17,-.09386,.06558,
-.103822,.048285,
-.110629,.029523,
-.114075,.009864,
-.114055,-.010095,
-.110569,-.029747,
-.103724,-.048495,
-.09386,-.06558,
-.09745,-.06917,
-.107981,-.051197,
-.115231,-.031669,
-.118979,-.011178,
-.119113,.009652,
-.115627,.030189,
-.108628,.049809,
-.098328,.067916,
-.09745,.06917,
-.09386,.06558,
90.*
4,1,17,-.06558,-.09386,
-.048285,-.103822,
-.029523,-.110629,
-.009864,-.114075,
.010095,-.114055,
.029747,-.110569,
.048495,-.103724,
.06558,-.09386,
.06917,-.09745,
.051197,-.107981,
.031669,-.115231,
.011178,-.118979,
-.009652,-.119113,
-.030189,-.115627,
-.049809,-.108628,
-.067916,-.098328,
-.06917,-.09745,
-.06558,-.09386,
90.*
4,1,17,.09386,-.06558,
.103822,-.048285,
.110629,-.029523,
.114075,-.009864,
.114055,.010095,
.110569,.029747,
.103724,.048495,
.09386,.06558,
.09745,.06917,
.107981,.051197,
.115231,.031669,
.118979,.011178,
.119113,-.009652,
.115627,-.030189,
.108628,-.049809,
.098328,-.067916,
.09745,-.06917,
.09386,-.06558,
90.*
4,1,17,.06558,.09386,
.048285,.103822,
.029523,.110629,
.009864,.114075,
-.010095,.114055,
-.029747,.110569,
-.048495,.103724,
-.06558,.09386,
-.06917,.09745,
-.051197,.107981,
-.031669,.115231,
-.011178,.118979,
.009652,.119113,
.030189,.115627,
.049809,.108628,
.067916,.098328,
.06917,.09745,
.06558,.09386,
90.*
%
%ADD26MACRO26*%
%ADD15C,.032*%
%ADD16C,.063*%
%ADD12C,.036*%
%ADD13C,.068*%
%ADD22C,.069*%
%AMMACRO24*
4,1,15,.00398,.00044,
.003999,.000208,
.004004,-.000025,
.003996,-.000258,
.00398,-.00044,
.00483,-.00129,
.004897,-.001007,
.004947,-.000721,
.004981,-.000432,
.004997,-.000141,
.004997,.000149,
.00498,.00044,
.004946,.000729,
.004895,.001015,
.00483,.00129,
.00398,.00044,
90.*
4,1,15,.00044,-.00398,
.000208,-.003999,
-.000025,-.004004,
-.000258,-.003996,
-.00044,-.00398,
-.00129,-.00483,
-.001007,-.004897,
-.000721,-.004947,
-.000432,-.004981,
-.000141,-.004997,
.000149,-.004997,
.00044,-.00498,
.000729,-.004946,
.001015,-.004895,
.00129,-.00483,
.00044,-.00398,
90.*
4,1,15,-.00398,-.00044,
-.003999,-.000208,
-.004004,.000025,
-.003996,.000258,
-.00398,.00044,
-.00483,.00129,
-.004897,.001007,
-.004947,.000721,
-.004981,.000432,
-.004997,.000141,
-.004997,-.000149,
-.00498,-.00044,
-.004946,-.000729,
-.004895,-.001015,
-.00483,-.00129,
-.00398,-.00044,
90.*
4,1,15,-.00044,.00398,
-.000208,.003999,
.000025,.004004,
.000258,.003996,
.00044,.00398,
.00129,.00483,
.001007,.004897,
.000721,.004947,
.000432,.004981,
.000141,.004997,
-.000149,.004997,
-.00044,.00498,
-.000729,.004946,
-.001015,.004895,
-.00129,.00483,
-.00044,.00398,
90.*
%
%ADD24MACRO24*%
%AMMACRO17*
4,1,15,.00398,.00044,
.003999,.000208,
.004004,-.000025,
.003996,-.000258,
.00398,-.00044,
.00483,-.00129,
.004897,-.001007,
.004947,-.000721,
.004981,-.000432,
.004997,-.000141,
.004997,.000149,
.00498,.00044,
.004946,.000729,
.004895,.001015,
.00483,.00129,
.00398,.00044,
0.0*
4,1,15,.00044,-.00398,
.000208,-.003999,
-.000025,-.004004,
-.000258,-.003996,
-.00044,-.00398,
-.00129,-.00483,
-.001007,-.004897,
-.000721,-.004947,
-.000432,-.004981,
-.000141,-.004997,
.000149,-.004997,
.00044,-.00498,
.000729,-.004946,
.001015,-.004895,
.00129,-.00483,
.00044,-.00398,
0.0*
4,1,15,-.00398,-.00044,
-.003999,-.000208,
-.004004,.000025,
-.003996,.000258,
-.00398,.00044,
-.00483,.00129,
-.004897,.001007,
-.004947,.000721,
-.004981,.000432,
-.004997,.000141,
-.004997,-.000149,
-.00498,-.00044,
-.004946,-.000729,
-.004895,-.001015,
-.00483,-.00129,
-.00398,-.00044,
0.0*
4,1,15,-.00044,.00398,
-.000208,.003999,
.000025,.004004,
.000258,.003996,
.00044,.00398,
.00129,.00483,
.001007,.004897,
.000721,.004947,
.000432,.004981,
.000141,.004997,
-.000149,.004997,
-.00044,.00498,
-.000729,.004946,
-.001015,.004895,
-.00129,.00483,
-.00044,.00398,
0.0*
%
%ADD17MACRO17*%
%AMMACRO23*
4,1,14,.0267,.01255,
.028474,.007723,
.029382,.002661,
.029398,-.002481,
.02852,-.007549,
.026776,-.012386,
.0267,-.01255,
.03042,-.01628,
.032785,-.01075,
.034154,-.004894,
.034484,.001111,
.033768,.007082,
.032025,.012838,
.03042,.01628,
.0267,.01255,
270.*
4,1,14,.01255,-.0267,
.007723,-.028474,
.002661,-.029382,
-.002481,-.029398,
-.007549,-.02852,
-.012386,-.026776,
-.01255,-.0267,
-.01628,-.03042,
-.01075,-.032785,
-.004894,-.034154,
.001111,-.034484,
.007082,-.033768,
.012838,-.032025,
.01628,-.03042,
.01255,-.0267,
270.*
4,1,14,-.0267,-.01255,
-.028474,-.007723,
-.029382,-.002661,
-.029398,.002481,
-.02852,.007549,
-.026776,.012386,
-.0267,.01255,
-.03042,.01628,
-.032785,.01075,
-.034154,.004894,
-.034484,-.001111,
-.033768,-.007082,
-.032025,-.012838,
-.03042,-.01628,
-.0267,-.01255,
270.*
4,1,14,-.01255,.0267,
-.007723,.028474,
-.002661,.029382,
.002481,.029398,
.007549,.02852,
.012386,.026776,
.01255,.0267,
.01628,.03042,
.01075,.032785,
.004894,.034154,
-.001111,.034484,
-.007082,.033768,
-.012838,.032025,
-.01628,.03042,
-.01255,.0267,
270.*
%
%ADD23MACRO23*%
%ADD19C,.143*%
%ADD11C,.17*%
%ADD21C,.127*%
%ADD20C,.154*%
%ADD27C,.239*%
%ADD10C,.168*%
%ADD18C,.178*%
%ADD14C,.198*%
%AMMACRO25*
4,1,15,.00398,.00044,
.003999,.000208,
.004004,-.000025,
.003996,-.000258,
.00398,-.00044,
.00483,-.00129,
.004897,-.001007,
.004947,-.000721,
.004981,-.000432,
.004997,-.000141,
.004997,.000149,
.00498,.00044,
.004946,.000729,
.004895,.001015,
.00483,.00129,
.00398,.00044,
180.*
4,1,15,.00044,-.00398,
.000208,-.003999,
-.000025,-.004004,
-.000258,-.003996,
-.00044,-.00398,
-.00129,-.00483,
-.001007,-.004897,
-.000721,-.004947,
-.000432,-.004981,
-.000141,-.004997,
.000149,-.004997,
.00044,-.00498,
.000729,-.004946,
.001015,-.004895,
.00129,-.00483,
.00044,-.00398,
180.*
4,1,15,-.00398,-.00044,
-.003999,-.000208,
-.004004,.000025,
-.003996,.000258,
-.00398,.00044,
-.00483,.00129,
-.004897,.001007,
-.004947,.000721,
-.004981,.000432,
-.004997,.000141,
-.004997,-.000149,
-.00498,-.00044,
-.004946,-.000729,
-.004895,-.001015,
-.00483,-.00129,
-.00398,-.00044,
180.*
4,1,15,-.00044,.00398,
-.000208,.003999,
.000025,.004004,
.000258,.003996,
.00044,.00398,
.00129,.00483,
.001007,.004897,
.000721,.004947,
.000432,.004981,
.000141,.004997,
-.000149,.004997,
-.00044,.00498,
-.000729,.004946,
-.001015,.004895,
-.00129,.00483,
-.00044,.00398,
180.*
%
%ADD25MACRO25*%
%ADD28C,.02*%
%ADD29C,.006*%
%ADD33C,.12304*%
%ADD32C,.15004*%
%ADD31C,.13904*%
%ADD30C,.16604*%
%ADD34C,.3937*%
G75*
%LPD*%
G75*
G36*
G01X-6000Y-6000D02*
X212693D01*
Y1974504D01*
X-6000D01*
Y-6000D01*
G37*
%LPC*%
G75*
G36*
G01X48250Y1583917D02*
G03X48232Y1581722I2350J-1117D01*
G01X48250Y1581682D01*
Y1581189D01*
X50689Y1578750D01*
X184811D01*
X188311Y1582250D01*
X202689D01*
X203689Y1581250D01*
Y1346137D01*
G02X202964Y1345905I-400J1D01*
G03Y1311575I-24027J-17165D01*
G02X203689Y1311343I325J-233D01*
G01Y477838D01*
G02X203006Y477555I-400J0D01*
G01X202311Y478250D01*
X129189D01*
X127250Y476311D01*
Y445689D01*
X127939Y445000D01*
X113250Y430311D01*
Y376189D01*
X116250Y373189D01*
Y354311D01*
X113250Y351311D01*
Y313689D01*
X138750Y288189D01*
Y255689D01*
X145189Y249250D01*
X184811D01*
X188750Y253189D01*
Y311811D01*
X178250Y322311D01*
Y444250D01*
X203689D01*
Y43307D01*
G02X202756Y42374I-933J0D01*
G01X72834D01*
G03X72602Y42370I4J-6941D01*
G01X71592D01*
X71459Y42236D01*
X71401Y42224D01*
G03X66044Y36867I1434J-6791D01*
G01X66032Y36809D01*
X65898Y36676D01*
Y35666D01*
G03X65894Y35434I6937J-236D01*
G01Y3937D01*
G02X64961Y3004I-933J0D01*
G01X3937D01*
G02X3004Y3937I0J933D01*
G01Y1324491D01*
G02X3689Y1324772I400J0D01*
G03Y1352394I14027J13811D01*
G02X3004Y1352675I-285J281D01*
G01Y1964567D01*
G02X3937Y1965500I933J0D01*
G01X64961D01*
G02X65894Y1964567I0J-933D01*
G01Y1933070D01*
G03X65898Y1932838I6941J4D01*
G01Y1931828D01*
X66032Y1931695D01*
X66044Y1931637D01*
G03X71401Y1926280I6791J1434D01*
G01X71459Y1926268D01*
X71592Y1926134D01*
X72602D01*
G03X72834Y1926130I236J6937D01*
G01X137309D01*
X137750Y1925689D01*
Y1897189D01*
X144250Y1890689D01*
Y1866311D01*
X141689Y1863750D01*
X129811D01*
X120311Y1873250D01*
X62189D01*
X59250Y1870311D01*
Y1752311D01*
X49750Y1742811D01*
Y1620189D01*
X52000Y1617939D01*
Y1615061D01*
X48250Y1611311D01*
Y1602417D01*
G03Y1600183I2350J-1117D01*
G01Y1596417D01*
G03Y1594183I2350J-1117D01*
G01Y1590417D01*
G03Y1588183I2350J-1117D01*
G01Y1583917D01*
G37*
G36*
G01X54811Y1617250D02*
X51250Y1620811D01*
Y1742189D01*
X60750Y1751689D01*
Y1869689D01*
X62811Y1871750D01*
X119689D01*
X128750Y1862689D01*
Y1784464D01*
X126231Y1783204D01*
X126003Y1783142D01*
X125961Y1783069D01*
X125887Y1783032D01*
X125812Y1782808D01*
X124000Y1779637D01*
X123995Y1779636D01*
X123847Y1779368D01*
X123695Y1779102D01*
X123696Y1779097D01*
X123694Y1779093D01*
X123778Y1778798D01*
X123858Y1778503D01*
X123863Y1778500D01*
X124699Y1775574D01*
X124690Y1775558D01*
X124783Y1775278D01*
X124864Y1774995D01*
X124881Y1774986D01*
X124887Y1774968D01*
X125150Y1774836D01*
X125407Y1774694D01*
X125426Y1774699D01*
X128750Y1773036D01*
Y1675689D01*
X136689Y1667750D01*
X183689D01*
X184750Y1666689D01*
Y1618311D01*
X183689Y1617250D01*
X84983D01*
G03X81117I-1933J-1250D01*
G01X54811D01*
G37*
G36*
G01X85344Y1615750D02*
X184689D01*
X187250Y1613189D01*
Y1583311D01*
X184189Y1580250D01*
X51311D01*
X49750Y1581811D01*
Y1610689D01*
X54811Y1615750D01*
X80756D01*
X80786Y1615586D01*
G03X85314I2264J414D01*
G01X85344Y1615750D01*
G37*
G36*
G01X176750Y444250D02*
Y321689D01*
X187250Y311189D01*
Y253811D01*
X184189Y250750D01*
X145811D01*
X140250Y256311D01*
Y288811D01*
X114750Y314311D01*
Y350689D01*
X117750Y353689D01*
Y373811D01*
X114750Y376811D01*
Y429689D01*
X129311Y444250D01*
X159588D01*
G03X163612I2012J1650D01*
G01X176750D01*
G37*
G36*
G01X201689Y476750D02*
X203689Y474750D01*
Y445750D01*
X129311D01*
X128750Y446311D01*
Y475689D01*
X129811Y476750D01*
X140504D01*
G03X143496I1496J1750D01*
G01X201689D01*
G37*
G36*
G01X190250Y1583750D02*
Y1583811D01*
X188750Y1585311D01*
Y1613811D01*
X186250Y1616311D01*
Y1667311D01*
X184311Y1669250D01*
X137311D01*
X130250Y1676311D01*
Y1773323D01*
X130310Y1773442D01*
X130250Y1773622D01*
Y1773811D01*
X130156Y1773905D01*
X130113Y1774032D01*
X129944Y1774116D01*
X129811Y1774250D01*
X129677D01*
X126131Y1776023D01*
X125308Y1778902D01*
X127039Y1781931D01*
X129677Y1783250D01*
X129811D01*
X129944Y1783384D01*
X130113Y1783468D01*
X130156Y1783595D01*
X130250Y1783689D01*
Y1783878D01*
X130310Y1784058D01*
X130250Y1784177D01*
Y1862250D01*
X142311D01*
X145750Y1865689D01*
Y1891311D01*
X139250Y1897811D01*
Y1925689D01*
X139691Y1926130D01*
X202756D01*
G02X203689Y1925197I0J-933D01*
G01Y1584750D01*
X202689Y1583750D01*
X190250D01*
G37*
%LPD*%
G75*
G36*
G01X123065Y447960D02*
X123009Y447948D01*
X119311Y444250D01*
X91726D01*
G02X87931Y444189I-1926J1750D01*
G01X87873Y444250D01*
X87250D01*
Y435811D01*
X96250Y426811D01*
Y374189D01*
X93750Y371689D01*
Y353311D01*
X94811Y352250D01*
X96811D01*
X99750Y349311D01*
Y319811D01*
X119250Y300311D01*
Y255689D01*
X114811Y251250D01*
X77689D01*
X70250Y258689D01*
Y281189D01*
X68189Y283250D01*
X40689D01*
X37250Y286689D01*
Y436311D01*
X45439Y444500D01*
X39250Y450689D01*
Y473811D01*
X44689Y479250D01*
X61193D01*
G02X63807I1307J-2250D01*
G01X106445D01*
G02X109755I1655J-1600D01*
G01X121311D01*
X122816Y477745D01*
X122838Y477732D01*
G02X123732Y476838I-1338J-2232D01*
G01X123745Y476816D01*
X125250Y475311D01*
Y450189D01*
X125052Y449991D01*
X125040Y449935D01*
G02X123065Y447960I-2540J565D01*
G37*
G54D33*
X80709Y139409D03*
X149606D03*
Y309409D03*
G54D32*
X80709Y119409D03*
X149606D03*
Y329409D03*
G54D31*
X47244Y68110D03*
Y501338D03*
Y761181D03*
Y1207323D03*
Y1467165D03*
Y1900393D03*
G54D30*
X29921Y24803D03*
Y111417D03*
Y458031D03*
Y544646D03*
Y717874D03*
Y804488D03*
X30000Y1164000D03*
X29921Y1250630D03*
Y1423858D03*
Y1510472D03*
Y1857086D03*
Y1943701D03*
G54D34*
X179134Y78740D03*
X27559Y157480D03*
X179133Y570866D03*
X27559Y629921D03*
X179134Y1161417D03*
X27559Y1811023D03*
X179134Y1889764D03*
%LPC*%
G75*
G36*
G01X85750Y444250D02*
Y435189D01*
X94750Y426189D01*
Y374811D01*
X92250Y372311D01*
Y352689D01*
X94189Y350750D01*
X96189D01*
X98250Y348689D01*
Y319189D01*
X117750Y299689D01*
Y256311D01*
X114189Y252750D01*
X78311D01*
X71750Y259311D01*
Y281811D01*
X68811Y284750D01*
X41311D01*
X38750Y287311D01*
Y435689D01*
X47311Y444250D01*
X62693D01*
G03X65307I1307J2250D01*
G01X85750D01*
G37*
G36*
G01X123750Y474689D02*
Y450811D01*
X118689Y445750D01*
X46311D01*
X40750Y451311D01*
Y473189D01*
X45311Y477750D01*
X120689D01*
X123750Y474689D01*
G37*
%LPD*%
G75*
G54D33*
X80709Y309409D03*
G54D32*
Y329409D03*
G54D26*
X96457Y1747835D03*
Y1823031D03*
X161417Y1747835D03*
Y1823031D03*
G54D15*
X32425Y177900D03*
X26450Y274750D03*
X34200Y284800D03*
X32600Y290500D03*
X25500Y321200D03*
X29500Y343500D03*
X23100Y342400D03*
X32675Y299500D03*
X23400Y353500D03*
X34000Y448000D03*
X29500Y410500D03*
X33200Y468900D03*
X14000Y476000D03*
X28800Y533700D03*
X5304Y548800D03*
Y528900D03*
X5094Y574500D03*
X29500Y586500D03*
X23450Y577491D03*
X25148Y570800D03*
X27000Y573800D03*
X4594Y749000D03*
Y714000D03*
X5000Y1355000D03*
X26700Y1529800D03*
X28000Y1596800D03*
X13300Y1644300D03*
X35500Y1670500D03*
X31400Y1648200D03*
X13300Y1689600D03*
X19542Y1710518D03*
X29100Y1721550D03*
X34000Y1691500D03*
X19200Y1707000D03*
X25000Y1763800D03*
X22000Y1787800D03*
X27400Y1899400D03*
X74000Y60500D03*
X79000Y65500D03*
X75000Y67500D03*
X84500Y56500D03*
X81500Y75500D03*
X63500Y63500D03*
X59600Y125800D03*
X75300Y155300D03*
X49924Y153261D03*
X53000Y171500D03*
X65000Y166300D03*
X60350Y151950D03*
X39300Y181100D03*
X63500Y179300D03*
X53400Y191300D03*
X39300Y175500D03*
X43700Y181200D03*
X43400Y174325D03*
X52700Y162300D03*
X64400Y183400D03*
X52500Y175200D03*
X70500Y190200D03*
X54400Y217000D03*
X65200Y207850D03*
X57424Y232974D03*
X42720Y233990D03*
X65000Y241500D03*
Y235400D03*
X54200Y207850D03*
Y220700D03*
X51700Y234800D03*
X41100Y231000D03*
X71400Y208150D03*
X69900Y236600D03*
X77900Y229034D03*
X70600Y217600D03*
X74800Y231800D03*
X69400Y226100D03*
X61300Y229400D03*
X38000Y228500D03*
X75300Y211300D03*
X85676Y231100D03*
X72100Y221700D03*
X49700Y209700D03*
X53500Y199700D03*
X47800Y199200D03*
X64000Y199700D03*
X60300Y275700D03*
X57500Y268500D03*
X68000Y268000D03*
X70600Y250500D03*
X42500Y260200D03*
X36000Y260386D03*
X58936Y256289D03*
X52500Y248500D03*
X50800Y266400D03*
X54000Y275600D03*
X45800Y277800D03*
X43400Y272300D03*
X78000Y429500D03*
X51000Y529500D03*
X66000Y550500D03*
X71445Y532192D03*
X72397Y528297D03*
X77800Y540300D03*
X49700Y568900D03*
X65000Y561500D03*
X78400Y583700D03*
X70350Y558850D03*
X54600Y573400D03*
X82000Y652000D03*
X66200Y653500D03*
X84200Y643865D03*
X75571Y692496D03*
X53000Y673500D03*
X57684Y697639D03*
X64000Y666600D03*
X52500Y682500D03*
X78494Y697835D03*
X53000Y695100D03*
X39800Y681400D03*
X86597Y681103D03*
X43388Y694286D03*
X49500Y703500D03*
X46500Y705500D03*
X44500Y697500D03*
X60900Y670200D03*
X60500Y682540D03*
X76100Y686900D03*
X83850Y678109D03*
X73000Y728000D03*
X71500Y735500D03*
X73500Y732000D03*
X86500Y723500D03*
X57500Y844500D03*
X72400Y822900D03*
X51200Y827000D03*
X61207Y828350D03*
X49600Y889400D03*
X59500Y881600D03*
X57500Y890300D03*
X56000Y885500D03*
X64600Y882700D03*
X61600Y885200D03*
X67200Y888800D03*
X54300Y915500D03*
X54000Y996500D03*
X70800Y990500D03*
X57500Y987800D03*
Y984300D03*
X83500Y976300D03*
Y972800D03*
X83000Y979800D03*
X53800Y1006200D03*
X53500Y1025500D03*
X56000Y1021500D03*
X54500Y1035500D03*
X51000Y1018000D03*
X64500Y1099000D03*
X37500Y1099823D03*
X70500Y1161500D03*
X73163Y1158780D03*
X68800Y1178800D03*
X39400Y1381300D03*
X44500Y1380500D03*
X45500Y1400000D03*
X80000Y1472000D03*
X83200Y1455500D03*
X45000Y1428000D03*
X36400Y1523400D03*
X67700Y1568700D03*
X43500Y1620700D03*
X42700Y1606000D03*
X38400Y1596700D03*
X83000Y1619703D03*
X83050Y1616000D03*
X42500Y1673000D03*
X44500Y1678000D03*
X43600Y1668300D03*
X43300Y1646600D03*
X45500Y1690000D03*
X41500Y1692000D03*
X40300Y1703900D03*
X44100Y1685200D03*
X45300Y1776300D03*
X52500Y1756000D03*
X55900Y1881500D03*
X62000Y1877000D03*
X57900Y1899800D03*
X65300Y1886600D03*
X38700Y1893800D03*
X41500Y1889500D03*
X60300Y1892300D03*
X47000Y1886200D03*
X79900Y1923000D03*
X92500Y73000D03*
X88253Y65500D03*
X117600Y234900D03*
X122100Y230100D03*
X127200Y246000D03*
X122500Y441000D03*
X108100Y477650D03*
X108900Y541300D03*
X102700Y541000D03*
X106300Y553200D03*
X110400Y550800D03*
X87700Y528000D03*
X132500Y539621D03*
X115300Y551800D03*
X129000Y597000D03*
X124200Y568400D03*
X119800Y568300D03*
X133500Y575500D03*
X137000Y589900D03*
X133500Y582000D03*
X134600Y586700D03*
X88000Y586500D03*
X101000Y583000D03*
X96000Y588000D03*
X89000Y595000D03*
X87000Y591000D03*
X135000Y561500D03*
X121000Y581500D03*
X124900Y582000D03*
X91300Y577000D03*
X92200Y553800D03*
X116000Y596900D03*
X113655Y599363D03*
X128900Y580500D03*
X122300Y575000D03*
X131135Y639554D03*
X87000Y648000D03*
X122500Y653650D03*
X117400Y653100D03*
X134600Y665600D03*
X130000Y700500D03*
X122500D03*
X114500D03*
X105500Y702500D03*
X93000Y698500D03*
X88500Y700000D03*
X98000Y698500D03*
Y703000D03*
X100200Y663900D03*
X118127Y663400D03*
X109005Y665890D03*
X114000Y663350D03*
X130000Y753000D03*
Y746000D03*
X119500Y757500D03*
Y746500D03*
Y739500D03*
X113500Y729000D03*
Y736000D03*
Y747000D03*
Y756000D03*
Y721000D03*
X106000Y709000D03*
X98000Y708000D03*
X130000Y764000D03*
X118700Y840700D03*
X98900Y822900D03*
X114900Y824100D03*
X106404Y840700D03*
X100300Y841000D03*
X111500Y851600D03*
X101500Y874200D03*
X102300Y863438D03*
X107164Y862285D03*
X113400Y862200D03*
X125400Y983600D03*
Y992000D03*
X97300Y990800D03*
X94000Y971800D03*
X104000Y1062500D03*
Y1049500D03*
X127200Y1015200D03*
X105000Y1181000D03*
X119500Y1261000D03*
X119000Y1255968D03*
X128700Y1408000D03*
X135601Y1416200D03*
X134500Y1420000D03*
X125000Y1398500D03*
X100860Y1402260D03*
X111000Y1394000D03*
X125100Y1402500D03*
X131174Y1412700D03*
X89000Y1428171D03*
X110000Y1429500D03*
X132000Y1436500D03*
X112750Y1491250D03*
X121000Y1506500D03*
X113000D03*
X117000D03*
X109000D03*
X133000Y1505500D03*
X128999Y1506499D03*
X125000Y1506500D03*
X135008Y1508245D03*
X132300Y1491100D03*
X108500Y1569000D03*
X113200Y1622800D03*
Y1619300D03*
X91100Y1922800D03*
X128900Y1923300D03*
X104600Y1923400D03*
X133500Y1906500D03*
X149500Y52000D03*
X146960Y432400D03*
X142000Y478500D03*
X165300Y481100D03*
X147000Y529900D03*
X156300Y552100D03*
X142500Y550000D03*
X162500Y527900D03*
X159850Y541800D03*
X182588Y542288D03*
X145800Y594400D03*
X142100Y581400D03*
X160000Y562500D03*
X147900Y588100D03*
X138900Y650100D03*
X139200Y653900D03*
X174196Y628196D03*
X150978Y687775D03*
X142648Y665429D03*
X165433Y692372D03*
X161000Y674000D03*
X157500Y664500D03*
X147000Y703000D03*
X149000Y677000D03*
X155200Y679500D03*
X161500Y691700D03*
X150700D03*
X153192Y705890D03*
X146000Y755000D03*
X166000Y751500D03*
X170000Y745500D03*
X161600Y739800D03*
X161500Y747500D03*
X146000Y726000D03*
X165900Y717300D03*
X146000Y738000D03*
X175100Y710000D03*
X158600Y752600D03*
X146000Y765500D03*
Y796500D03*
Y782500D03*
X166000Y760000D03*
X166500Y775500D03*
X161500Y759000D03*
Y768000D03*
Y778000D03*
X146500Y812000D03*
X146000Y824000D03*
X180000Y856000D03*
X162000Y817500D03*
X174000Y834500D03*
X168000Y830000D03*
X180000Y872500D03*
X179500Y884000D03*
X179900Y900900D03*
X157800Y898000D03*
X147500Y900500D03*
X180000Y960400D03*
X179900Y925700D03*
X179800Y941400D03*
X180000Y912500D03*
X143000Y953032D03*
X146500Y953030D03*
X149772Y954121D03*
X152747Y952474D03*
X163100Y978600D03*
X163200Y985200D03*
X149800Y1008700D03*
X179000Y1005000D03*
X180500Y973200D03*
X150500Y976500D03*
X155000Y974500D03*
X155500Y1030000D03*
X153500Y1033500D03*
X151500Y1030500D03*
X159500Y1062000D03*
X163000Y1042500D03*
X146500Y1397100D03*
X155900D03*
X139900Y1415100D03*
X142500Y1420500D03*
X169000Y1426750D03*
X158500Y1466500D03*
X151500Y1438500D03*
X157500Y1454800D03*
X142000Y1494800D03*
X147500Y1498000D03*
X153500Y1496500D03*
X143518Y1567520D03*
X177500Y1569500D03*
X141300Y1625000D03*
X169876Y1626303D03*
X141500Y1621600D03*
X173270Y1626517D03*
X201500Y165000D03*
X191400Y432405D03*
X202210Y638500D03*
X201500Y691500D03*
X202500Y666000D03*
X201500Y726500D03*
X202500Y755500D03*
X201500Y777000D03*
X201389Y797000D03*
X202000Y859500D03*
X202500Y822000D03*
Y846500D03*
X202000Y890000D03*
X202210Y903500D03*
X202000Y875000D03*
X202500Y945500D03*
X202000Y918000D03*
X202500Y962000D03*
X201500Y931500D03*
X202500Y1006000D03*
Y977500D03*
X201500Y991000D03*
X202000Y1037000D03*
Y1052000D03*
X201500Y1019000D03*
X201389Y1067000D03*
X201500Y1082500D03*
X195000Y1112000D03*
X201500Y1147000D03*
X202000Y1212000D03*
X202500Y1179000D03*
X202000Y1246000D03*
X201500Y1306500D03*
X202500Y1280000D03*
X201500Y1359500D03*
Y1350000D03*
X201700Y1388300D03*
X201500Y1413000D03*
X202400Y1444000D03*
X201389Y1425500D03*
X202210Y1462000D03*
X194500Y1510000D03*
Y1505500D03*
X196500Y1572000D03*
G54D12*
X8594Y6500D03*
X31500Y5500D03*
X20000Y6000D03*
X17000Y36500D03*
X32000Y40000D03*
X5594Y87000D03*
Y53500D03*
X29500Y53000D03*
X26000Y87000D03*
X30800Y130300D03*
X4594Y120500D03*
X34400Y95300D03*
X14000Y141000D03*
X23500Y124000D03*
X15000Y131500D03*
X14500Y100500D03*
Y112500D03*
X4500Y105500D03*
X5000Y137500D03*
X22500Y190000D03*
X29700Y191400D03*
X5594Y153500D03*
X4594Y187500D03*
X16500Y175000D03*
X27000Y182000D03*
X14000Y184000D03*
X4500Y170500D03*
X21500Y241500D03*
X4594Y234000D03*
X24000Y212000D03*
X29000Y200500D03*
X13000Y244000D03*
X13500Y230500D03*
X13000Y212500D03*
X5000Y221000D03*
X12500Y197500D03*
X4500Y202500D03*
X28050Y256950D03*
X5094Y278000D03*
X6094Y257000D03*
X13500Y279000D03*
Y295000D03*
X5500Y295500D03*
X12500Y266500D03*
X5500Y269500D03*
X5000Y247500D03*
X19721Y267203D03*
X5594Y312000D03*
X5304Y342500D03*
X4900Y328000D03*
X13500Y303500D03*
X13000Y321000D03*
X4594Y396500D03*
X6500Y375000D03*
X27000Y371000D03*
X4800Y356200D03*
X23700Y363900D03*
X29500Y364500D03*
X27000Y377500D03*
Y384000D03*
Y389500D03*
X4594Y421000D03*
X5304Y444500D03*
Y440500D03*
X5000Y408500D03*
X5304Y434500D03*
X26500Y440000D03*
X26000Y432500D03*
X23800Y410700D03*
X5094Y469500D03*
X5000Y495000D03*
X4700Y458200D03*
X5000Y486500D03*
X5094Y600000D03*
X34100Y566600D03*
X13510Y597990D03*
X14000Y614000D03*
X4594Y625000D03*
X18000Y608000D03*
X6000Y612000D03*
Y646000D03*
X26000Y656500D03*
X5594Y688500D03*
X5304Y661000D03*
X14000Y659000D03*
X23000Y677500D03*
X32000Y666000D03*
X28000Y706000D03*
X8000Y678000D03*
X31000Y700500D03*
X20000Y696000D03*
X6000Y698000D03*
Y706500D03*
X31000Y747000D03*
X22000Y746000D03*
X24000Y756000D03*
X27000Y750000D03*
X26000Y732000D03*
X18000Y724000D03*
Y732500D03*
Y712000D03*
X6000Y722000D03*
Y730500D03*
X5594Y778000D03*
X6500Y799000D03*
X9500Y804000D03*
X30000Y782000D03*
X16100Y794600D03*
X5594Y844500D03*
X6094Y819500D03*
X30500D03*
X10000Y811500D03*
X24000Y846000D03*
X24500Y853500D03*
X16000Y828000D03*
Y814000D03*
Y856000D03*
Y842000D03*
X32000Y858000D03*
Y844000D03*
X4500Y833500D03*
Y857500D03*
X26053Y828247D03*
X5094Y897500D03*
X5594Y869000D03*
X16000Y906000D03*
X32000Y886000D03*
Y872000D03*
X18000Y884000D03*
Y870000D03*
X5000Y883500D03*
X18500Y896500D03*
X23053Y861247D03*
X5304Y926000D03*
X4594Y954000D03*
X18000Y934000D03*
Y920000D03*
X16000Y962000D03*
Y948000D03*
X4500Y913000D03*
Y941500D03*
X34000Y944000D03*
Y934500D03*
X33500Y962500D03*
Y953000D03*
X26053Y938247D03*
X4594Y1013500D03*
X5594Y984500D03*
X28000Y992000D03*
X26000Y1010000D03*
X16000Y990000D03*
Y976000D03*
Y1014000D03*
Y1000000D03*
X4500Y970000D03*
Y997000D03*
X34000Y984000D03*
Y974500D03*
Y1008000D03*
X25053Y971247D03*
X4594Y1041500D03*
X6000Y1058000D03*
X33600Y1029900D03*
X16000Y1046000D03*
Y1032000D03*
X14000Y1060000D03*
X4500Y1029500D03*
X34000Y1017500D03*
X27553Y1029247D03*
X5094Y1074500D03*
X32000Y1114000D03*
X34000Y1102000D03*
Y1072000D03*
X28000D03*
X14000Y1074000D03*
Y1100000D03*
Y1086000D03*
X16000Y1110000D03*
X6000Y1096000D03*
X26100Y1088600D03*
X27218Y1097000D03*
X33550Y1080100D03*
X34000Y1144000D03*
X16000Y1124000D03*
Y1148000D03*
Y1134000D03*
Y1162000D03*
X6000Y1138000D03*
Y1118000D03*
Y1152000D03*
X26600Y1132400D03*
X24553Y1153247D03*
X5304Y1208000D03*
X4594Y1169500D03*
X24000Y1180000D03*
X16000Y1176000D03*
X5094Y1268500D03*
X8500Y1237000D03*
X30000Y1240000D03*
X16000Y1262000D03*
Y1244000D03*
X28000Y1266000D03*
X6000Y1252000D03*
X22000Y1232000D03*
X31500Y1222000D03*
X6500Y1302000D03*
X17700Y1283000D03*
X34000Y1312000D03*
X6000Y1318000D03*
X12000Y1274000D03*
Y1294000D03*
X28000Y1286000D03*
Y1300000D03*
Y1320000D03*
X19800Y1315400D03*
X13500Y1365000D03*
X8000Y1368000D03*
X30800Y1403900D03*
X31500Y1397500D03*
X5304Y1409400D03*
X4594Y1382000D03*
X7500Y1376500D03*
X32000Y1391500D03*
X4800Y1460700D03*
X4594Y1435500D03*
X34000Y1465900D03*
X5304Y1504100D03*
Y1522100D03*
X4600Y1484800D03*
X34000Y1477600D03*
X29500Y1495800D03*
X5304Y1576200D03*
Y1540500D03*
X26600Y1570100D03*
X26900Y1547900D03*
Y1559100D03*
X4594Y1607500D03*
X33100Y1587400D03*
X26700Y1579800D03*
X7500Y1640200D03*
X5304Y1659000D03*
X4700Y1676100D03*
X4594Y1632000D03*
X29000Y1671000D03*
X19250Y1663100D03*
X5304Y1723500D03*
X4900Y1708000D03*
X13100Y1728900D03*
X4594Y1691000D03*
X30000Y1731000D03*
X4594Y1775000D03*
Y1751000D03*
X12600Y1753800D03*
X13100Y1742600D03*
X12900Y1765200D03*
X14500Y1832500D03*
X12600Y1792800D03*
X12500Y1782500D03*
X4594Y1878500D03*
X14500Y1863500D03*
X5000Y1864100D03*
X18600Y1871400D03*
X4594Y1850000D03*
X15000Y1854900D03*
X27500Y1883500D03*
X14500Y1842000D03*
X28000Y1876500D03*
X29000Y1841000D03*
X13100Y1933900D03*
X24800Y1926500D03*
X5094Y1921000D03*
X4594Y1902000D03*
X35000Y1933500D03*
X35300Y1925300D03*
X34500Y1963200D03*
X16100Y1950700D03*
X5094Y1944500D03*
X15500Y1942500D03*
X4500Y1936000D03*
X6500Y1962000D03*
X25000Y1962500D03*
X12500Y1959000D03*
X63594Y7000D03*
Y25500D03*
X40594Y6000D03*
X49000Y18500D03*
X43000Y27000D03*
X64500Y40000D03*
X64000Y17000D03*
X53000Y5000D03*
X51500Y53000D03*
X74000Y45000D03*
X85000D03*
X63098Y119103D03*
X52000Y115600D03*
X62598Y141103D03*
X51700Y131700D03*
X71000Y131859D03*
X37000Y124000D03*
X51900Y145700D03*
X86000Y152000D03*
X69000Y153000D03*
X73500Y146000D03*
X60800Y147700D03*
X78200Y481700D03*
X74942Y530983D03*
X72500Y595900D03*
X56800Y576950D03*
X36000Y554000D03*
X79122Y565700D03*
X79458Y578758D03*
X69800Y574200D03*
X80900Y668400D03*
X86443Y662853D03*
X84504Y666353D03*
X56710Y681069D03*
X71800Y701300D03*
X69100Y698006D03*
X74100Y669398D03*
X50000Y712500D03*
Y749000D03*
X40000Y746500D03*
X36000Y730000D03*
X46000Y726000D03*
X82000Y806500D03*
X44000Y782000D03*
X42000Y802000D03*
Y788000D03*
X47600Y796800D03*
X79000Y857000D03*
X81500Y837500D03*
X82500Y814000D03*
X48000Y816000D03*
X38000Y834000D03*
Y820000D03*
X46000Y848000D03*
Y834000D03*
X78300Y832600D03*
X77600Y849100D03*
X87000Y839500D03*
X48100Y853400D03*
X45600Y827500D03*
X37500Y912000D03*
Y907500D03*
X77000Y871500D03*
X62500Y862000D03*
X61500Y876500D03*
X78000Y878500D03*
X77500Y907000D03*
X85500Y903000D03*
X78300Y893900D03*
X77000Y863000D03*
X83400Y878600D03*
X47000Y877600D03*
X40900Y901500D03*
X41000Y931899D03*
X86500Y932000D03*
X61500Y938500D03*
X81500Y940000D03*
X75500Y936500D03*
X69500Y939000D03*
X55500Y955500D03*
X56500Y940000D03*
X62500Y924500D03*
X70000Y914500D03*
Y925500D03*
X76500Y927000D03*
X85500Y915000D03*
X77500Y917000D03*
X87000Y997500D03*
X55500Y968000D03*
X76400Y999100D03*
X37700Y991600D03*
X39300Y1105800D03*
X67302Y1133490D03*
X78292Y1148041D03*
X64500Y1165700D03*
X79044Y1144112D03*
X66000Y1149500D03*
X37500Y1118900D03*
X74000Y1132000D03*
X40000Y1136000D03*
Y1156000D03*
X77293Y1129729D03*
X58000Y1206000D03*
X46000Y1218000D03*
X60000Y1194000D03*
X61000Y1173000D03*
X54000Y1184000D03*
X44000Y1194000D03*
X42000Y1242000D03*
X50000Y1244000D03*
X42000Y1266000D03*
X58000Y1250000D03*
Y1222000D03*
X39500Y1231000D03*
X51800Y1231600D03*
X50100Y1261500D03*
X42000Y1290000D03*
X50000Y1318000D03*
X40000Y1278000D03*
Y1298000D03*
X44000Y1306000D03*
X58000Y1312000D03*
Y1292000D03*
Y1272000D03*
X52000Y1296300D03*
X61000Y1363500D03*
X52500Y1368500D03*
X39000Y1333500D03*
X44000Y1326000D03*
Y1340000D03*
X54000Y1330000D03*
X72000Y1360000D03*
X83800Y1365900D03*
X84000Y1352000D03*
X81500Y1382000D03*
Y1416500D03*
Y1404000D03*
X71800Y1373900D03*
X83800Y1391900D03*
X70500Y1378500D03*
X69400Y1402900D03*
X39500Y1407900D03*
X55600Y1381700D03*
X48900Y1390500D03*
X60900D03*
X56700Y1400100D03*
X60600Y1423600D03*
X68800Y1417800D03*
X58800Y1412400D03*
X49000Y1413300D03*
X72900Y1393600D03*
X74900Y1408800D03*
X75600Y1420300D03*
X61500Y1380000D03*
X86900Y1451000D03*
X70400Y1444500D03*
X79000Y1436400D03*
X76200Y1430700D03*
X66500Y1433500D03*
X53100Y1430700D03*
X42600Y1444200D03*
X49100Y1448400D03*
X68500Y1454600D03*
X74500Y1461800D03*
X72300Y1469800D03*
X59000Y1444500D03*
X77000Y1449000D03*
X59000Y1472000D03*
X58100Y1459300D03*
X83500Y1469500D03*
X63000Y1482300D03*
X42700Y1500000D03*
X72700Y1480500D03*
X46500Y1484900D03*
X64100Y1495400D03*
X73000Y1491200D03*
X43300Y1518500D03*
X49500Y1505000D03*
X45400Y1523800D03*
X85000Y1490000D03*
X46600Y1541100D03*
X45300Y1563600D03*
X45900Y1532800D03*
X37900Y1570000D03*
X38800Y1541700D03*
X38300Y1561800D03*
X44400Y1592100D03*
X38300Y1579600D03*
X43200Y1634800D03*
X42500Y1699500D03*
X44600Y1724400D03*
X44900Y1706800D03*
X53000Y1750500D03*
X36700Y1764700D03*
X56500Y1769300D03*
X44900Y1740300D03*
X39179Y1792306D03*
X39700Y1869700D03*
X46700Y1857700D03*
X46500Y1850200D03*
X44500Y1833500D03*
X46500Y1844000D03*
Y1865500D03*
X45100Y1933400D03*
X54500Y1889500D03*
X63500Y1928000D03*
X61500Y1922500D03*
X46000Y1923000D03*
X54000Y1928500D03*
X36500Y1900500D03*
X63500Y1963000D03*
X63594Y1935500D03*
X61600Y1954700D03*
X41100Y1957500D03*
X55300Y1959100D03*
X43500Y1945000D03*
X49053Y1951747D03*
X135000Y50000D03*
Y70000D03*
X128500Y89000D03*
X118000Y54500D03*
X124000Y74500D03*
X105000Y55000D03*
Y45000D03*
X95000D03*
X115000D03*
X125000D03*
X135000D03*
X137200Y123600D03*
X127700Y119200D03*
X128700Y104200D03*
X131000Y138100D03*
X118000Y124500D03*
X119000Y109500D03*
X118000Y142500D03*
X95000Y143000D03*
X105000D03*
X95000Y125000D03*
X105000D03*
X95000Y134000D03*
X129000Y160100D03*
X137900Y171400D03*
X131000Y150100D03*
X118000Y154500D03*
X95000Y155000D03*
X105000D03*
X131800Y289700D03*
X130900Y259100D03*
X111500Y390000D03*
X101300Y390100D03*
X105500Y390000D03*
Y406500D03*
X101500D03*
X107000Y426500D03*
X98000D03*
X102500D03*
X111200Y426400D03*
X110500Y406500D03*
X117000Y530000D03*
X90630Y602020D03*
X103100Y587600D03*
X87595Y581300D03*
X112800Y653500D03*
X108200Y655825D03*
X88967Y659749D03*
X90674Y663367D03*
X121500Y683500D03*
X119576Y687008D03*
X120702Y690847D03*
X100600Y670600D03*
X134100Y674500D03*
X119000Y673300D03*
X87310Y676796D03*
X124800Y696600D03*
X129800Y696800D03*
X98000Y674327D03*
X102913Y673973D03*
X107113Y674001D03*
X108500Y695500D03*
X103500D03*
X115000Y704500D03*
X99001Y694866D03*
X125000Y734000D03*
X116500Y752000D03*
X125000Y751000D03*
X125500Y741500D03*
X130000Y736500D03*
X125000Y758500D03*
X120500Y732500D03*
X120000Y717500D03*
X123000Y808500D03*
X114500Y805500D03*
X123000Y800000D03*
X122500Y792500D03*
X114000Y800000D03*
X113500Y792500D03*
X130000Y800000D03*
X129500Y792500D03*
X121500Y783500D03*
X121000Y776000D03*
X129500Y782000D03*
X129000Y774500D03*
X115200Y784200D03*
X115000Y773200D03*
X121000Y767900D03*
X95500Y841500D03*
X124500Y858000D03*
X123500Y842500D03*
Y816000D03*
X115000Y813000D03*
X129200Y830400D03*
X129800Y813500D03*
X124500Y825100D03*
X134500Y840500D03*
X90500Y831500D03*
X137500Y903000D03*
X135500Y909000D03*
X124000D03*
X113500Y909500D03*
X103500D03*
X94000Y910500D03*
X116053Y903247D03*
X127000Y903000D03*
X90000Y893000D03*
X102500Y893500D03*
X117500Y893000D03*
X135000D03*
X134500Y885500D03*
X137500Y876500D03*
X125000Y868500D03*
X107000Y903000D03*
X124500Y876500D03*
X126000Y892500D03*
X96053Y903247D03*
X125500Y944000D03*
X105000Y958000D03*
X96500Y916500D03*
X107000Y918000D03*
X135000D03*
X135500Y927500D03*
X115000Y920000D03*
X125500D03*
X126000Y930000D03*
X115500D03*
X99000Y953000D03*
X88500Y940500D03*
X120000Y916000D03*
X126000Y954000D03*
X124618Y959244D03*
X110000Y949500D03*
X117529Y948844D03*
X93000Y925500D03*
X133500Y938000D03*
X134000Y990500D03*
X125000Y967000D03*
X130500Y966000D03*
X124000Y971500D03*
X117000Y1008500D03*
X105500Y996000D03*
X95500Y999000D03*
X106500Y1008500D03*
X104000Y1014000D03*
X119000Y975000D03*
X136500Y967000D03*
X108500Y964000D03*
Y971000D03*
X114800Y1005000D03*
X135000Y975500D03*
X110500Y1041500D03*
X111500Y1030000D03*
Y1020000D03*
X110500Y1064500D03*
Y1051000D03*
X103500Y1042000D03*
Y1028500D03*
X116500Y1049000D03*
Y1035500D03*
Y1062500D03*
X117500Y1023500D03*
X120000Y1108000D03*
Y1102000D03*
X115000Y1108500D03*
X110500Y1112000D03*
X103500Y1073500D03*
X104500Y1095000D03*
X116500Y1076000D03*
X109000Y1083500D03*
X89000Y1167400D03*
X118500Y1166000D03*
X105000Y1196000D03*
X119300Y1191400D03*
X119500Y1177500D03*
Y1205500D03*
X92000Y1214500D03*
X104500Y1208000D03*
X94000Y1189000D03*
X91500Y1200000D03*
X99000Y1265500D03*
X119000Y1269000D03*
X117500Y1251000D03*
X112000Y1250500D03*
Y1244500D03*
X119300Y1245400D03*
Y1219400D03*
X119500Y1231500D03*
X124000Y1270000D03*
X104500Y1219500D03*
X92000Y1254000D03*
X103500Y1229000D03*
X92000Y1241500D03*
X103000Y1244900D03*
X91500Y1229000D03*
X99500Y1310000D03*
Y1294000D03*
X98000Y1282000D03*
X123800Y1283900D03*
X113800Y1287900D03*
X114000Y1274000D03*
X123800Y1311900D03*
X124000Y1298000D03*
X114000Y1318000D03*
X92000Y1295500D03*
X91500Y1314500D03*
X114500Y1296500D03*
X97800Y1327900D03*
X123800Y1337900D03*
X124000Y1324000D03*
X113800Y1331900D03*
X115800Y1363900D03*
X116000Y1350000D03*
X123800Y1365900D03*
X124000Y1352000D03*
X114500Y1370500D03*
X93800Y1353900D03*
X94000Y1340000D03*
Y1366000D03*
X90800Y1331200D03*
X105500Y1415000D03*
X99600Y1416500D03*
X100500Y1384500D03*
Y1389000D03*
X124000Y1376500D03*
X114000Y1376000D03*
X93800Y1379900D03*
Y1393200D03*
X93600Y1407100D03*
X97500Y1412000D03*
X89700Y1409700D03*
X110000Y1418000D03*
X137000Y1429200D03*
X126600Y1461500D03*
X133500Y1467100D03*
X132200Y1424800D03*
X94000Y1427800D03*
X87200Y1431900D03*
X87700Y1446500D03*
X87300Y1436000D03*
X95500Y1468000D03*
X103700Y1470300D03*
X113024Y1452079D03*
X117122Y1448001D03*
X117195Y1456070D03*
X121338Y1452021D03*
X117024Y1452000D03*
X87200Y1440000D03*
X99800Y1455600D03*
X109500Y1438000D03*
X98500Y1428400D03*
X117000Y1435200D03*
X133799Y1440699D03*
X91300Y1488600D03*
X97000Y1503100D03*
X93500Y1482700D03*
X99170Y1485790D03*
X118000Y1922000D03*
X184000Y55500D03*
X174000D03*
X164000D03*
X153000Y90500D03*
X154000Y75500D03*
X145000Y45000D03*
X155000D03*
X165000D03*
X175000D03*
X185000D03*
X180500Y112000D03*
X186000Y143000D03*
X187500Y130500D03*
X167000D03*
X176000Y131000D03*
X165500Y95500D03*
X174500Y143500D03*
X171500Y105500D03*
X170500Y120500D03*
X146500Y131859D03*
X154000Y105500D03*
X147600Y150900D03*
X165300Y145200D03*
X173500Y151500D03*
X185500D03*
X138800Y162100D03*
X141300Y298100D03*
X187500Y338000D03*
X180850Y348800D03*
X184500Y325500D03*
X188500Y364100D03*
X188300Y368600D03*
X181800Y369000D03*
X181100Y364050D03*
X186600Y425750D03*
X144600Y533800D03*
X147500Y551500D03*
X182600Y546900D03*
X180500Y595000D03*
X171600Y595400D03*
X145500Y604000D03*
X141800Y559250D03*
X150500Y596000D03*
X153500Y574359D03*
X140700Y576600D03*
X152700Y618803D03*
X170349Y619949D03*
X167300Y653800D03*
X159700Y652000D03*
X175800Y617635D03*
X164950Y615700D03*
X180500Y627771D03*
X165600Y630269D03*
X151432Y661741D03*
X148995Y658568D03*
X185000Y673500D03*
X188100Y689100D03*
X176000Y679000D03*
Y665500D03*
X162300Y659100D03*
X183500Y698000D03*
X184700Y663900D03*
X165500Y677500D03*
X184500Y708500D03*
X181000Y729000D03*
Y715500D03*
X182500Y758500D03*
Y745000D03*
X172000Y757500D03*
X181500Y738500D03*
X169100Y722100D03*
X169000Y795500D03*
X163500Y805500D03*
X178000Y797500D03*
X187900Y785300D03*
X175000Y786500D03*
X173500Y777500D03*
Y764000D03*
X181700Y768400D03*
X165000Y786000D03*
X171500Y819500D03*
X177500Y812000D03*
Y826500D03*
X145500Y856500D03*
X140500Y846500D03*
X157500Y858000D03*
X185000Y843500D03*
X145500Y885000D03*
X143000Y910500D03*
X146000Y893000D03*
X184500Y879000D03*
Y865500D03*
X154700Y909700D03*
X156300Y877200D03*
X156500Y889000D03*
X187000Y891000D03*
X153500Y941000D03*
X141000Y938500D03*
X144000Y919500D03*
Y929000D03*
X154500Y926500D03*
X185000Y917500D03*
X182000Y950500D03*
X174000Y1012400D03*
X184000Y987500D03*
X146800Y1018900D03*
X143900Y1022700D03*
X166300Y1021300D03*
X182500Y1041500D03*
X183500Y1065500D03*
X182000Y1029500D03*
Y1016000D03*
X171000Y1046000D03*
Y1032500D03*
X175000Y1059000D03*
X160500Y1053500D03*
X181000Y1051000D03*
X164700Y1033600D03*
X176000Y1018500D03*
X171000Y1068000D03*
X166000Y1080000D03*
X173000Y1082000D03*
X165000Y1097000D03*
X181000Y1098500D03*
X175000Y1072500D03*
X160500Y1067000D03*
X187500Y1103500D03*
Y1090000D03*
X170000Y1103000D03*
Y1089500D03*
X157000Y1101500D03*
X159500Y1087500D03*
X181000Y1112500D03*
Y1079500D03*
X154600Y1111000D03*
X158500Y1075800D03*
X158595Y1110789D03*
X147500Y1165500D03*
X177102Y1129800D03*
X171502Y1129547D03*
X147500Y1186000D03*
X178644Y1202519D03*
X163344Y1181200D03*
X161500Y1227500D03*
X147500Y1221500D03*
X146500Y1241500D03*
X147000Y1265500D03*
X183500Y1241500D03*
X165000Y1264500D03*
X147500Y1288000D03*
Y1311000D03*
X164500Y1299500D03*
X147500Y1332000D03*
X147000Y1348000D03*
X147500Y1366500D03*
X147000Y1377000D03*
X146500Y1417619D03*
X173375Y1432500D03*
X149686Y1460007D03*
X152500Y1456000D03*
X194000Y55500D03*
X195000Y45000D03*
X200000Y55000D03*
Y65000D03*
Y75000D03*
Y85000D03*
X190500Y105000D03*
X189500Y120000D03*
X200000Y100000D03*
Y120000D03*
Y140000D03*
X191900Y167700D03*
X191700Y186500D03*
X201089Y181700D03*
X197500Y151500D03*
X191900Y244600D03*
X191800Y234900D03*
Y221100D03*
X191600Y206900D03*
X201500Y208000D03*
X201000Y222500D03*
X200500Y235000D03*
Y195900D03*
X202000Y295000D03*
Y274000D03*
Y254000D03*
X201089Y282600D03*
X202000Y264000D03*
Y340000D03*
Y328000D03*
X201089Y305500D03*
Y315500D03*
X201500Y397500D03*
Y378000D03*
X202000Y366500D03*
Y353000D03*
X192600Y392600D03*
X192471Y397355D03*
X201089Y388400D03*
X200500Y437500D03*
X201000Y430500D03*
X201089Y407000D03*
X200000Y420500D03*
X192400Y401900D03*
X192300Y410950D03*
X192409Y417655D03*
X201500Y544500D03*
X201089Y529500D03*
X201500Y552500D03*
X192400Y529400D03*
X191900Y538200D03*
X201500Y535000D03*
X192000Y543500D03*
X190500Y550500D03*
X202000Y578000D03*
Y586000D03*
Y595000D03*
X193700D03*
X194400Y586000D03*
X201089Y558000D03*
X201500Y564000D03*
X201089Y570600D03*
X202000Y607500D03*
X196500Y641500D03*
X192600Y633000D03*
X201500Y621500D03*
X202000Y650500D03*
X194000Y628500D03*
Y615000D03*
X192500Y645000D03*
X195000Y670000D03*
X197500Y685000D03*
X197000Y704000D03*
X202000Y676500D03*
X192500Y658500D03*
X191500Y692500D03*
X193100Y679000D03*
X196000Y718500D03*
X195500Y739000D03*
X197500Y753000D03*
X202000Y710000D03*
Y740500D03*
X191500Y724000D03*
Y710500D03*
Y746500D03*
X196000Y789500D03*
X196500Y797000D03*
X202000Y765000D03*
Y786000D03*
Y807500D03*
X191500Y760000D03*
X194500Y782500D03*
Y769000D03*
X196800Y828500D03*
X197000Y815000D03*
X190000Y823500D03*
X190500Y831000D03*
X201500Y835500D03*
X192500Y853000D03*
Y839500D03*
X192000Y879000D03*
Y865500D03*
X194000Y907000D03*
Y893500D03*
X192000Y934500D03*
Y921000D03*
Y962000D03*
Y948500D03*
X192500Y985500D03*
Y972000D03*
X195500Y1001000D03*
X190000Y1052000D03*
X195500Y1014500D03*
X193500Y1042500D03*
Y1029000D03*
X195000Y1061000D03*
Y1086500D03*
X194500Y1100500D03*
X195000Y1074500D03*
X201000Y1106500D03*
Y1093000D03*
X191800Y1280900D03*
X192500Y1543500D03*
Y1554000D03*
Y1533000D03*
Y1562500D03*
G54D16*
X31299Y230866D03*
Y220866D03*
Y210866D03*
Y348563D03*
Y338563D03*
Y358563D03*
Y903917D03*
Y923917D03*
Y913917D03*
Y1064587D03*
Y1054587D03*
Y1044587D03*
Y1619941D03*
Y1609941D03*
Y1629941D03*
Y1757638D03*
Y1747638D03*
Y1737638D03*
G54D13*
X15906Y48110D03*
Y58110D03*
Y68110D03*
Y78110D03*
Y88110D03*
Y481339D03*
Y491339D03*
Y501339D03*
Y511339D03*
Y521339D03*
Y741181D03*
Y751181D03*
Y761181D03*
Y771181D03*
Y781181D03*
Y1187323D03*
Y1197323D03*
Y1207323D03*
Y1217323D03*
Y1227323D03*
Y1447165D03*
Y1457165D03*
Y1467165D03*
Y1477165D03*
Y1487165D03*
Y1880394D03*
Y1890394D03*
Y1900394D03*
Y1910394D03*
Y1920394D03*
X138937Y1778819D03*
X128937D03*
X118937D03*
X165000Y1370500D03*
Y1390500D03*
Y1380500D03*
G54D22*
X80709Y161889D03*
Y171889D03*
Y181889D03*
Y191889D03*
Y204409D03*
Y214409D03*
Y224409D03*
Y234409D03*
Y244409D03*
X110709Y161889D03*
Y171889D03*
X100709Y161889D03*
Y171889D03*
X90709Y161889D03*
Y171889D03*
X110709Y181889D03*
Y191889D03*
X100709Y181889D03*
Y191889D03*
X90709Y181889D03*
Y191889D03*
X110709Y204409D03*
Y214409D03*
Y224409D03*
Y234409D03*
Y244409D03*
X100709Y204409D03*
Y214409D03*
Y224409D03*
Y234409D03*
Y244409D03*
X90709Y204409D03*
Y214409D03*
Y224409D03*
Y234409D03*
Y244409D03*
X179606Y161889D03*
Y171889D03*
X169606Y161889D03*
Y171889D03*
X159606Y161889D03*
Y171889D03*
X149606Y161889D03*
Y171889D03*
X179606Y181889D03*
Y191889D03*
X169606Y181889D03*
Y191889D03*
X159606Y181889D03*
Y191889D03*
X149606Y181889D03*
Y191889D03*
X179606Y204409D03*
Y214409D03*
Y224409D03*
Y234409D03*
Y244409D03*
X169606Y204409D03*
Y214409D03*
Y224409D03*
Y234409D03*
Y244409D03*
X159606Y204409D03*
Y214409D03*
Y224409D03*
Y234409D03*
Y244409D03*
X149606Y204409D03*
Y214409D03*
Y224409D03*
Y234409D03*
Y244409D03*
G54D24*
X76000Y296000D03*
X68000Y286000D03*
Y320000D03*
Y312000D03*
Y304000D03*
X74000Y390000D03*
X66000D03*
X58000D03*
X74000Y400000D03*
X66000D03*
X58000D03*
X74000Y408000D03*
X66000D03*
Y418000D03*
X74000D03*
X73700Y423000D03*
X66000Y426000D03*
X58000Y417500D03*
X71600Y1607700D03*
X58500D03*
X102000Y312000D03*
X104000Y304000D03*
X94000D03*
Y312000D03*
Y320000D03*
X134000Y396000D03*
X118000D03*
Y386000D03*
X134000D03*
Y404500D03*
Y414000D03*
X118000D03*
X134000Y424000D03*
X107000Y802400D03*
Y798200D03*
X106882Y794201D03*
X104000Y1605500D03*
X94500D03*
X182000Y296000D03*
X172000D03*
X162000D03*
X142000Y291000D03*
X143400Y318700D03*
X174000Y316000D03*
X164000D03*
X172000Y310000D03*
X182000D03*
X184000Y303000D03*
X176000Y302000D03*
X166000D03*
X143300Y343400D03*
X151300Y298200D03*
X150000Y386000D03*
Y396000D03*
Y404000D03*
Y414000D03*
Y424000D03*
X182500Y1599400D03*
X146000Y1612000D03*
X148000Y1606000D03*
X182500Y1592000D03*
X138500Y1606000D03*
X182500Y1584500D03*
G54D17*
X21600Y333800D03*
X33450Y574300D03*
X31600Y1024300D03*
X10500Y1648800D03*
X13900Y1706200D03*
X64000Y67553D03*
X64500Y53000D03*
X70454Y60031D03*
X42500Y254100D03*
X48500Y248600D03*
X86000Y296000D03*
X68000D03*
X64000Y446500D03*
Y451000D03*
X84500Y433000D03*
X58100Y431900D03*
X63096Y434540D03*
X68500Y434300D03*
X78200Y501000D03*
X82000Y483600D03*
X46000Y490500D03*
X71900Y501000D03*
X50100Y493000D03*
X42500D03*
X63300Y464400D03*
X64000Y455500D03*
Y460000D03*
X62500Y472900D03*
X62600Y468500D03*
X62500Y477000D03*
X52100Y513100D03*
X46500Y511000D03*
X46000Y516000D03*
X78500Y506700D03*
X71800Y506900D03*
X85000Y506400D03*
X84500Y514400D03*
X72100Y521800D03*
X79400D03*
X72000Y514800D03*
X78000D03*
X51700Y522500D03*
X63400Y581400D03*
X39096Y674917D03*
X43281Y674991D03*
X40000Y659000D03*
X69000Y726800D03*
X55700Y880000D03*
X64000Y980500D03*
X87000Y1064000D03*
X82094Y1112500D03*
X83500Y1072000D03*
Y1067000D03*
Y1076500D03*
X71100Y1171000D03*
X85200Y1515000D03*
X58500Y1519000D03*
X72000Y1514000D03*
X53500Y1519000D03*
X54500Y1574000D03*
X73900Y1535900D03*
X80000Y1531600D03*
X54300Y1541200D03*
X59500Y1541000D03*
X57500Y1562000D03*
X57000Y1568500D03*
X50600Y1589300D03*
Y1582800D03*
Y1595300D03*
Y1601300D03*
X55300Y1601100D03*
Y1595100D03*
Y1582600D03*
Y1589100D03*
X68700Y1603900D03*
X55400Y1613300D03*
X59500Y1667000D03*
X70000Y1668000D03*
X75500Y1679000D03*
X86000D03*
Y1669000D03*
X76000Y1646000D03*
X86000D03*
X76000Y1634000D03*
X86000D03*
Y1659500D03*
X75500D03*
X54000Y1646500D03*
X64500Y1646000D03*
X57500Y1634500D03*
X64000Y1634000D03*
X64500Y1658500D03*
X53500Y1659000D03*
X56000Y1695000D03*
Y1704500D03*
Y1712500D03*
X55500Y1723500D03*
X69000Y1684500D03*
X80500D03*
X62500Y1691500D03*
X65000Y1724000D03*
X62500Y1709000D03*
X72500Y1717000D03*
Y1699000D03*
X62500Y1700000D03*
X60000Y1730000D03*
X86500Y1713610D03*
Y1700110D03*
Y1726000D03*
X48400Y1746900D03*
X41600D03*
X38800Y1775000D03*
X64500Y1758500D03*
X55500Y1735500D03*
X65000Y1735000D03*
X79000Y1766500D03*
X65000Y1749000D03*
Y1768000D03*
Y1742500D03*
X71500Y1760000D03*
X72500Y1733000D03*
X87000Y1774110D03*
X42000Y1784400D03*
X81000Y1802000D03*
X73000Y1813000D03*
X64500Y1821500D03*
Y1812000D03*
Y1801500D03*
X65000Y1790000D03*
X72500Y1830000D03*
X72000Y1798000D03*
X86500Y1793110D03*
X75500Y1838500D03*
X63500Y1863000D03*
Y1856000D03*
X64000Y1844500D03*
Y1834000D03*
X73000Y1847000D03*
X85100Y1844500D03*
X85700Y1852300D03*
X109500Y62000D03*
X89500Y49500D03*
X99500Y61000D03*
X115000Y76500D03*
X109000D03*
X98500Y73000D03*
X115500Y59500D03*
X97000Y51500D03*
X91500Y88500D03*
Y92500D03*
X112000Y101000D03*
X104500D03*
X91000Y97000D03*
X93000Y107000D03*
X93900Y111800D03*
X93500Y101500D03*
X114000Y296000D03*
X106000D03*
X96000D03*
X122500Y450500D03*
X117000Y449000D03*
X89800Y446000D03*
X136000Y447000D03*
X131000D03*
X88500Y426500D03*
X135500Y441000D03*
X130000Y432000D03*
X129000Y485500D03*
X120000D03*
Y501500D03*
X110800Y482600D03*
X99800Y482000D03*
X110800Y488600D03*
X100000Y488000D03*
X110800Y500600D03*
X100000Y500000D03*
X129000Y501500D03*
X100000Y494000D03*
X110800Y494600D03*
X129000Y493500D03*
X120000D03*
X137000Y501500D03*
Y493000D03*
X136500Y485500D03*
X122500Y457500D03*
Y463500D03*
X121500Y475500D03*
X122500Y469500D03*
X117000Y455000D03*
Y460500D03*
Y466000D03*
Y471500D03*
X89800Y452900D03*
Y459000D03*
X111500Y473000D03*
X99500D03*
X89800Y464800D03*
X135500Y454000D03*
Y461000D03*
Y474500D03*
Y468000D03*
X130500Y454000D03*
Y461000D03*
Y468000D03*
Y474500D03*
X91300Y528200D03*
X129000Y517500D03*
X100000Y512000D03*
X129000Y509500D03*
X110800Y512600D03*
X120000Y517500D03*
X100000Y506000D03*
X110800Y506600D03*
X120000Y509500D03*
Y523500D03*
X129000D03*
X137000Y510000D03*
X137500Y523500D03*
X100000Y519100D03*
X137500Y517500D03*
X91250Y704700D03*
X91400Y1064100D03*
X95500Y1064000D03*
X97250Y1023500D03*
X101500Y1127500D03*
X106000D03*
X97000D03*
X97500Y1132500D03*
X93000Y1518700D03*
X94000Y1514000D03*
X87900Y1523400D03*
X124500Y1524000D03*
X129000Y1555500D03*
X111500Y1537500D03*
X122000Y1558000D03*
X114000Y1552000D03*
X122000D03*
X114000Y1558000D03*
X122000Y1564000D03*
X121800Y1569929D03*
X114000Y1564000D03*
X122000Y1576000D03*
X102000Y1544000D03*
Y1562000D03*
Y1550000D03*
Y1556000D03*
Y1568000D03*
X94000D03*
X116000Y1576000D03*
X115900Y1569700D03*
X129000Y1535000D03*
X136000Y1568000D03*
X94000Y1556000D03*
X129000Y1549000D03*
X122000Y1538000D03*
X136000Y1542000D03*
X122000Y1546000D03*
X129000Y1542500D03*
X136000Y1536000D03*
X114000Y1546000D03*
X128000Y1568000D03*
X136000Y1562000D03*
Y1555000D03*
X129000Y1562500D03*
X136000Y1548000D03*
X119000Y1529500D03*
X94000Y1550000D03*
Y1562000D03*
X136000Y1528000D03*
X122000Y1584000D03*
X116000D03*
Y1592000D03*
X122000D03*
X116000Y1600000D03*
X122000Y1612000D03*
X116000D03*
X122000Y1600000D03*
X128000Y1606000D03*
X113500Y1605500D03*
X117500Y1679000D03*
X125000D03*
X107500D03*
X117500Y1669000D03*
X127500D03*
X97000D03*
X107000D03*
X127000Y1646000D03*
X138000Y1634000D03*
X137500Y1659500D03*
X118000Y1646000D03*
X138000D03*
X117000Y1633500D03*
X127500Y1633000D03*
Y1659500D03*
X117500D03*
X108000Y1646000D03*
X106000Y1634000D03*
X107000Y1659500D03*
X96000Y1646000D03*
X96500Y1634000D03*
X97000Y1659500D03*
X122000Y1685500D03*
X91000Y1685000D03*
X103000D03*
X112500D03*
X108500Y1727000D03*
X98500Y1717000D03*
Y1696500D03*
X99000Y1707000D03*
X97500Y1679500D03*
X109500Y1719500D03*
X110000Y1709500D03*
X109500Y1699000D03*
X119500Y1710110D03*
Y1696610D03*
Y1725110D03*
X111500Y1768500D03*
X117500Y1732000D03*
X119500Y1760000D03*
X97500Y1775500D03*
X108268Y1777300D03*
X119500Y1747110D03*
X138000Y1824000D03*
X110500Y1801000D03*
X88500Y1785000D03*
X97500Y1796000D03*
X98000Y1786000D03*
X107768Y1789110D03*
X120000Y1811500D03*
X119500Y1796500D03*
X114000Y1843500D03*
X97000Y1850500D03*
X99500Y1862500D03*
X106500D03*
X114500D03*
X122500D03*
X120500Y1836500D03*
Y1850500D03*
X108500Y1851610D03*
X116948Y1892000D03*
X124500Y1892403D03*
X132000Y1892000D03*
X161600Y445900D03*
X161900Y451600D03*
X174500Y432000D03*
X162000D03*
X145500Y427000D03*
X142000Y432000D03*
X186500Y498000D03*
X144000Y501500D03*
X173600Y498800D03*
X169200Y482800D03*
X157100Y500000D03*
X144000Y493500D03*
Y486182D03*
X162000Y457600D03*
X161900Y463300D03*
X188500Y474500D03*
X186500Y513500D03*
X173700Y513900D03*
X144000Y517500D03*
X173500Y506000D03*
X144000Y509500D03*
X186500Y506000D03*
X166100Y527900D03*
X186500Y519000D03*
X174900Y523300D03*
X156800Y515400D03*
Y506900D03*
X154600Y581500D03*
X159250Y590250D03*
X155000Y1130500D03*
Y1125000D03*
Y1120000D03*
X148300Y1465000D03*
X174500Y1503500D03*
Y1509500D03*
X174000Y1515500D03*
Y1522000D03*
X148000Y1550000D03*
X170000Y1541000D03*
X148000Y1558000D03*
Y1528000D03*
Y1542000D03*
X168500Y1533500D03*
X170000Y1555000D03*
X161400Y1543500D03*
X150000Y1576000D03*
X156000Y1570000D03*
X154000Y1564000D03*
X170000Y1548500D03*
X169500Y1561500D03*
X161300Y1563100D03*
X148000Y1564000D03*
X156000Y1576000D03*
X168500Y1526000D03*
X166898Y1567102D03*
X150000Y1570000D03*
X156000Y1582000D03*
X156500Y1591000D03*
X150500Y1582000D03*
Y1591000D03*
X172000Y1606000D03*
X164000D03*
X156500Y1600000D03*
X156000Y1606000D03*
X150500Y1600000D03*
X141500Y1673000D03*
X176000Y1646000D03*
X166000D03*
X158000D03*
X148000D03*
X176000Y1632000D03*
X178000Y1659500D03*
X167500Y1632500D03*
X170000Y1659500D03*
X149000Y1632500D03*
X159000D03*
Y1659500D03*
X148500Y1660000D03*
X139000Y1696500D03*
Y1712500D03*
X138500Y1727500D03*
X181500Y1716500D03*
X158500D03*
X167500Y1716000D03*
X182000Y1726000D03*
Y1704000D03*
X168500Y1705000D03*
X158500D03*
X184500Y1696500D03*
X163000Y1697000D03*
X174268Y1697110D03*
X152000D03*
Y1710610D03*
Y1725610D03*
X185000Y1738500D03*
X183600Y1765100D03*
X169000Y1781500D03*
X162500Y1773000D03*
X152500Y1771110D03*
X173268Y1776000D03*
X139000Y1800500D03*
X156500Y1782000D03*
X155500Y1798500D03*
X166500Y1798000D03*
X179000Y1798500D03*
X185500Y1804500D03*
X186000Y1790000D03*
X162000D03*
X172768Y1790110D03*
X152000D03*
X139000Y1851000D03*
X138500Y1839500D03*
X185000Y1852500D03*
X161500D03*
X183100Y1838300D03*
X160500Y1877500D03*
X152500Y1883100D03*
X173000Y1852610D03*
X151500Y1851110D03*
X184500Y1920500D03*
X170000D03*
X161000Y1901500D03*
X162100Y1912000D03*
X151900Y1891400D03*
X146300Y1913700D03*
X142400Y1923800D03*
X176700Y1923900D03*
X177700Y1912800D03*
X157900Y1923100D03*
X190239Y447449D03*
X195600Y447500D03*
X192000Y490000D03*
Y498000D03*
X200300Y498100D03*
X199500Y489400D03*
X189900Y467500D03*
Y460500D03*
X190400Y453500D03*
X195000Y467500D03*
X194500Y474500D03*
X195000Y460500D03*
X195500Y453500D03*
X192000Y513500D03*
Y506000D03*
X190200Y523400D03*
X201089Y523500D03*
X193600Y519100D03*
X200100Y513600D03*
X199800Y506000D03*
X201200Y519200D03*
X196500Y1586000D03*
Y1595000D03*
X192500Y1617000D03*
Y1626500D03*
X196500Y1606500D03*
X192500Y1634000D03*
Y1670500D03*
Y1664000D03*
Y1653000D03*
Y1648000D03*
X192650Y1641500D03*
X198500Y1713500D03*
X198000Y1691500D03*
X197500Y1776500D03*
X198000Y1754000D03*
Y1735500D03*
Y1818500D03*
X197500Y1800500D03*
X198500Y1859500D03*
X198000Y1838500D03*
X195000Y1874000D03*
X200000Y1882000D03*
X200500Y1876500D03*
X201500Y1900500D03*
X190500Y1924000D03*
X201000Y1923000D03*
X195500Y1905000D03*
X201200Y1890500D03*
X201100Y1908800D03*
G54D23*
X80709Y256929D03*
Y266929D03*
Y276929D03*
Y286929D03*
X110709Y256929D03*
Y266929D03*
X100709Y256929D03*
Y266929D03*
X90709Y256929D03*
Y266929D03*
X110709Y276929D03*
Y286929D03*
X100709Y276929D03*
Y286929D03*
X90709Y276929D03*
Y286929D03*
X179606Y256929D03*
Y266929D03*
X169606Y256929D03*
Y266929D03*
X159606Y256929D03*
Y266929D03*
X149606Y256929D03*
Y266929D03*
X179606Y276929D03*
Y286929D03*
X169606Y276929D03*
Y286929D03*
X159606Y276929D03*
Y286929D03*
X149606Y276929D03*
Y286929D03*
G54D11*
X29921Y24803D03*
Y111417D03*
Y458031D03*
Y544646D03*
Y717874D03*
Y804488D03*
X30000Y1164000D03*
X29921Y1250630D03*
Y1423858D03*
Y1510472D03*
Y1857086D03*
Y1943701D03*
G54D19*
X47244Y68110D03*
Y501338D03*
Y761181D03*
Y1207323D03*
Y1467165D03*
Y1900393D03*
G54D20*
X80709Y119409D03*
Y329409D03*
X149606Y119409D03*
Y329409D03*
G54D21*
X80709Y139409D03*
Y309409D03*
X149606Y139409D03*
Y309409D03*
G54D27*
X178937Y1328740D03*
G54D10*
X-222440Y19685D03*
Y1948818D03*
X643700Y19685D03*
Y1948818D03*
G54D18*
X27559Y629921D03*
X17716Y1338583D03*
X27559Y1811023D03*
X179134Y78740D03*
X179133Y570866D03*
X179134Y1161417D03*
G54D14*
X27559Y157480D03*
X179134Y1889764D03*
G54D25*
X58000Y426000D03*
Y408000D03*
X81000Y410500D03*
X86400D03*
X91900D03*
X118000Y424000D03*
Y404000D03*
%LPC*%
G75*
G54D28*
G01X-448201Y-66763D02*
X-480201D01*
G01X-448201Y-82763D02*
Y-162763D01*
G01Y-118263D02*
X752899D01*
G01X-448201Y-162763D02*
X752899D01*
G01X-452201Y-66763D02*
G02I-12000J0D01*
G01X-457351D02*
G02I-6850J0D01*
G01X-464201Y-82763D02*
Y-50763D01*
G01X-448201Y-82763D02*
X752899D01*
G01X-34601D02*
Y-162763D01*
G01X102899Y-82763D02*
Y-162763D01*
G01X217899Y-82763D02*
Y-162763D01*
G01X385399Y-82763D02*
Y-162763D01*
G01X555399Y-82763D02*
Y-162763D01*
G01X752899Y-82763D02*
Y-162763D01*
G01X780899Y-66763D02*
G02I-12000J0D01*
G01X775749D02*
G02I-6850J0D01*
G01X768899Y-82763D02*
Y-50763D01*
G01X784899Y-66763D02*
X752899D01*
G54D29*
G01X-430254Y-152763D02*
Y-135263D01*
G01X-421958D02*
X-430254Y-146055D01*
G01X-420648Y-152763D02*
X-426543Y-141097D01*
G01X-412973Y-152763D02*
Y-135263D01*
X-402929Y-152763D01*
Y-135263D01*
G01X-390451Y-152763D02*
X-392198Y-152471D01*
X-393726Y-151305D01*
X-395036Y-149555D01*
X-395910Y-147513D01*
X-396346Y-145180D01*
Y-142846D01*
X-395910Y-140513D01*
X-395036Y-138471D01*
X-393726Y-136722D01*
X-392198Y-135555D01*
X-390451Y-135263D01*
X-388705Y-135555D01*
X-387176Y-136722D01*
X-385866Y-138471D01*
X-384992Y-140513D01*
X-384556Y-142846D01*
Y-145180D01*
X-384992Y-147513D01*
X-385866Y-149555D01*
X-387176Y-151305D01*
X-388705Y-152471D01*
X-390451Y-152763D01*
G01X-377536D02*
X-368366Y-135263D01*
G01X-377536D02*
X-368366Y-152763D01*
G01X-362001Y-158596D02*
X-348901D01*
G01X-342099Y-152763D02*
Y-135263D01*
X-333803D01*
G01X-336859Y-143721D02*
X-342099D01*
G01X-325910Y-152763D02*
X-320451Y-135263D01*
X-314992Y-152763D01*
G01X-316958Y-146638D02*
X-323945D01*
G01X-307973Y-152763D02*
Y-135263D01*
X-297929Y-152763D01*
Y-135263D01*
G01X-263148Y-136722D02*
X-264458Y-135846D01*
X-265986Y-135263D01*
X-267733D01*
X-269698Y-136138D01*
X-271226Y-137596D01*
X-272318Y-139347D01*
X-273191Y-142263D01*
X-273410Y-144888D01*
X-272973Y-147513D01*
X-272318Y-149263D01*
X-271008Y-151013D01*
X-269479Y-152180D01*
X-267951Y-152763D01*
X-266423D01*
X-264894Y-152180D01*
X-263584Y-151305D01*
X-262492Y-150139D01*
G01X-250451Y-152763D02*
X-252198Y-152471D01*
X-253726Y-151305D01*
X-255036Y-149555D01*
X-255910Y-147513D01*
X-256346Y-145180D01*
Y-142846D01*
X-255910Y-140513D01*
X-255036Y-138471D01*
X-253726Y-136722D01*
X-252198Y-135555D01*
X-250451Y-135263D01*
X-248705Y-135555D01*
X-247176Y-136722D01*
X-245866Y-138471D01*
X-244992Y-140513D01*
X-244556Y-142846D01*
Y-145180D01*
X-244992Y-147513D01*
X-245866Y-149555D01*
X-247176Y-151305D01*
X-248705Y-152471D01*
X-250451Y-152763D01*
G01X-237973D02*
Y-135263D01*
X-227929Y-152763D01*
Y-135263D01*
G01X-215451D02*
Y-152763D01*
G01X-220473Y-135263D02*
X-210429D01*
G01X-202318Y-152763D02*
Y-135263D01*
X-196859D01*
X-195113Y-136138D01*
X-194021Y-137305D01*
X-193584Y-139638D01*
X-194021Y-141972D01*
X-195331Y-143430D01*
X-196859Y-144305D01*
X-202318D01*
G01X-196859D02*
X-193584Y-152763D01*
G01X-180451D02*
X-182198Y-152471D01*
X-183726Y-151305D01*
X-185036Y-149555D01*
X-185910Y-147513D01*
X-186346Y-145180D01*
Y-142846D01*
X-185910Y-140513D01*
X-185036Y-138471D01*
X-183726Y-136722D01*
X-182198Y-135555D01*
X-180451Y-135263D01*
X-178705Y-135555D01*
X-177176Y-136722D01*
X-175866Y-138471D01*
X-174992Y-140513D01*
X-174556Y-142846D01*
Y-145180D01*
X-174992Y-147513D01*
X-175866Y-149555D01*
X-177176Y-151305D01*
X-178705Y-152471D01*
X-180451Y-152763D01*
G01X-167318Y-135263D02*
Y-152763D01*
X-158584D01*
G01X-126205Y-143430D02*
X-125331Y-142555D01*
X-124676Y-141097D01*
X-124239Y-139054D01*
X-124676Y-137305D01*
X-125549Y-136138D01*
X-127078Y-135263D01*
X-132973D01*
Y-152763D01*
X-125768D01*
X-124239Y-151597D01*
X-123366Y-149846D01*
X-122929Y-147805D01*
X-123366Y-145763D01*
X-124676Y-144013D01*
X-126205Y-143430D01*
X-132973D01*
G01X-110451Y-152763D02*
X-112198Y-152471D01*
X-113726Y-151305D01*
X-115036Y-149555D01*
X-115910Y-147513D01*
X-116346Y-145180D01*
Y-142846D01*
X-115910Y-140513D01*
X-115036Y-138471D01*
X-113726Y-136722D01*
X-112198Y-135555D01*
X-110451Y-135263D01*
X-108705Y-135555D01*
X-107176Y-136722D01*
X-105866Y-138471D01*
X-104992Y-140513D01*
X-104556Y-142846D01*
Y-145180D01*
X-104992Y-147513D01*
X-105866Y-149555D01*
X-107176Y-151305D01*
X-108705Y-152471D01*
X-110451Y-152763D01*
G01X-98410D02*
X-92951Y-135263D01*
X-87492Y-152763D01*
G01X-89458Y-146638D02*
X-96445D01*
G01X-79818Y-152763D02*
Y-135263D01*
X-74359D01*
X-72613Y-136138D01*
X-71521Y-137305D01*
X-71084Y-139638D01*
X-71521Y-141972D01*
X-72831Y-143430D01*
X-74359Y-144305D01*
X-79818D01*
G01X-74359D02*
X-71084Y-152763D01*
G01X-62754D02*
Y-135263D01*
X-58388D01*
X-56641Y-136138D01*
X-55331Y-137305D01*
X-54239Y-139054D01*
X-53366Y-141097D01*
X-53148Y-144013D01*
X-53366Y-146930D01*
X-54239Y-148972D01*
X-55331Y-150722D01*
X-56641Y-151888D01*
X-58388Y-152763D01*
X-62754D01*
G01X-282378Y-107763D02*
Y-90263D01*
X-276701Y-104846D01*
X-271024Y-90263D01*
Y-107763D01*
G01X-259201D02*
X-260511Y-107471D01*
X-261821Y-106305D01*
X-262695Y-104263D01*
X-263131Y-101930D01*
X-262695Y-99596D01*
X-261821Y-97555D01*
X-260511Y-96388D01*
X-259201Y-96097D01*
X-257891Y-96388D01*
X-256581Y-97555D01*
X-255708Y-99596D01*
X-255489Y-101930D01*
X-255708Y-104263D01*
X-256581Y-106305D01*
X-257891Y-107471D01*
X-259201Y-107763D01*
G01X-237771Y-90263D02*
Y-107763D01*
G01Y-105139D02*
X-238644Y-106597D01*
X-239955Y-107471D01*
X-241483Y-107763D01*
X-243229Y-107180D01*
X-244539Y-105722D01*
X-245413Y-103972D01*
X-245631Y-101930D01*
X-245413Y-99888D01*
X-244539Y-98138D01*
X-243229Y-96680D01*
X-241483Y-96097D01*
X-239955Y-96388D01*
X-238863Y-96972D01*
X-237771Y-98138D01*
G01X-227476Y-99888D02*
X-220489D01*
X-221144Y-97846D01*
X-222236Y-96680D01*
X-223764Y-96097D01*
X-225293Y-96388D01*
X-226603Y-97263D01*
X-227476Y-99305D01*
X-227913Y-101055D01*
Y-102805D01*
X-227476Y-104555D01*
X-226384Y-106305D01*
X-225074Y-107471D01*
X-223546Y-107763D01*
X-222018Y-107180D01*
X-220489Y-105430D01*
G01X-206701Y-107763D02*
Y-90263D01*
G01X-14018Y-107763D02*
Y-90263D01*
X-8778D01*
X-7031Y-91138D01*
X-5721Y-93180D01*
X-5284Y-95513D01*
X-5721Y-97846D01*
X-6813Y-99596D01*
X-8778Y-100472D01*
X-14018D01*
G01X12652Y-91722D02*
X11342Y-90846D01*
X9814Y-90263D01*
X8067D01*
X6102Y-91138D01*
X4574Y-92596D01*
X3482Y-94347D01*
X2609Y-97263D01*
X2390Y-99888D01*
X2827Y-102513D01*
X3482Y-104263D01*
X4792Y-106013D01*
X6321Y-107180D01*
X7849Y-107763D01*
X9377D01*
X10906Y-107180D01*
X12216Y-106305D01*
X13308Y-105139D01*
G01X27095Y-98430D02*
X27969Y-97555D01*
X28624Y-96097D01*
X29061Y-94054D01*
X28624Y-92305D01*
X27751Y-91138D01*
X26222Y-90263D01*
X20327D01*
Y-107763D01*
X27532D01*
X29061Y-106597D01*
X29934Y-104846D01*
X30371Y-102805D01*
X29934Y-100763D01*
X28624Y-99013D01*
X27095Y-98430D01*
X20327D01*
G01X36299Y-113596D02*
X49399D01*
G01X55327Y-107763D02*
Y-90263D01*
X65371Y-107763D01*
Y-90263D01*
G01X77849Y-107763D02*
X76102Y-107471D01*
X74574Y-106305D01*
X73264Y-104555D01*
X72390Y-102513D01*
X71954Y-100180D01*
Y-97846D01*
X72390Y-95513D01*
X73264Y-93471D01*
X74574Y-91722D01*
X76102Y-90555D01*
X77849Y-90263D01*
X79595Y-90555D01*
X81124Y-91722D01*
X82434Y-93471D01*
X83308Y-95513D01*
X83744Y-97846D01*
Y-100180D01*
X83308Y-102513D01*
X82434Y-104555D01*
X81124Y-106305D01*
X79595Y-107471D01*
X77849Y-107763D01*
G01X-901Y-152763D02*
Y-135263D01*
X-3521Y-138763D01*
G01Y-152763D02*
X1719D01*
G01X12451Y-138180D02*
X13761Y-136430D01*
X15289Y-135555D01*
X17036Y-135263D01*
X19219Y-135846D01*
X20747Y-137305D01*
X21184Y-139054D01*
X20966Y-140805D01*
X20092Y-142263D01*
X15726Y-145180D01*
X13761Y-147221D01*
X12451Y-150139D01*
X12014Y-152763D01*
X21184D01*
G01X36719D02*
Y-135263D01*
X28640Y-147805D01*
X39558D01*
G01X46796Y-149263D02*
X48105Y-151305D01*
X49852Y-152471D01*
X51817Y-152763D01*
X53564Y-152471D01*
X55311Y-151013D01*
X56402Y-149263D01*
X56621Y-147513D01*
X56184Y-145472D01*
X54656Y-144013D01*
X53127Y-143430D01*
X51162D01*
G01X53127D02*
X54437Y-142555D01*
X55529Y-141097D01*
X55966Y-139347D01*
X55529Y-137596D01*
X54437Y-136138D01*
X52472Y-135263D01*
X50507Y-135555D01*
X48542Y-136722D01*
G01X64296Y-149263D02*
X65605Y-151305D01*
X67352Y-152471D01*
X69317Y-152763D01*
X71064Y-152471D01*
X72811Y-151013D01*
X73902Y-149263D01*
X74121Y-147513D01*
X73684Y-145472D01*
X72156Y-144013D01*
X70627Y-143430D01*
X68662D01*
G01X70627D02*
X71937Y-142555D01*
X73029Y-141097D01*
X73466Y-139347D01*
X73029Y-137596D01*
X71937Y-136138D01*
X69972Y-135263D01*
X68007Y-135555D01*
X66042Y-136722D01*
G01X128690Y-90263D02*
X134149Y-107763D01*
X139608Y-90263D01*
G01X156016Y-107763D02*
X147282D01*
Y-90263D01*
X156016D01*
G01X152522Y-98721D02*
X147282D01*
G01X164782Y-107763D02*
Y-90263D01*
X170241D01*
X171987Y-91138D01*
X173079Y-92305D01*
X173516Y-94638D01*
X173079Y-96972D01*
X171769Y-98430D01*
X170241Y-99305D01*
X164782D01*
G01X170241D02*
X173516Y-107763D01*
G01X186649Y-108346D02*
X186212Y-108055D01*
Y-107471D01*
X186649Y-107180D01*
X187086Y-107471D01*
Y-108055D01*
X186649Y-108346D01*
G01X147501Y-138180D02*
X148811Y-136430D01*
X150339Y-135555D01*
X152086Y-135263D01*
X154269Y-135846D01*
X155797Y-137305D01*
X156234Y-139054D01*
X156016Y-140805D01*
X155142Y-142263D01*
X150776Y-145180D01*
X148811Y-147221D01*
X147501Y-150139D01*
X147064Y-152763D01*
X156234D01*
G01X163690D02*
X169149Y-135263D01*
X174608Y-152763D01*
G01X172642Y-146638D02*
X165655D01*
G01X253482Y-90263D02*
Y-107763D01*
X262216D01*
G01X279279D02*
Y-96097D01*
G01Y-98138D02*
X278406Y-96972D01*
X277095Y-96388D01*
X275567Y-96097D01*
X274039Y-96680D01*
X272729Y-97846D01*
X271855Y-99596D01*
X271419Y-101930D01*
X271855Y-104263D01*
X272729Y-106013D01*
X274039Y-107180D01*
X275567Y-107763D01*
X277095Y-107471D01*
X278406Y-106597D01*
X279279Y-105430D01*
G01X288264Y-113013D02*
X289574Y-113596D01*
X291321Y-113013D01*
X292412Y-111847D01*
X293286Y-110388D01*
X294595Y-105722D01*
X297434Y-96097D01*
G01X290447D02*
X294595Y-105722D01*
G01X307074Y-99888D02*
X314061D01*
X313406Y-97846D01*
X312314Y-96680D01*
X310786Y-96097D01*
X309257Y-96388D01*
X307947Y-97263D01*
X307074Y-99305D01*
X306637Y-101055D01*
Y-102805D01*
X307074Y-104555D01*
X308166Y-106305D01*
X309476Y-107471D01*
X311004Y-107763D01*
X312532Y-107180D01*
X314061Y-105430D01*
G01X324792Y-107763D02*
Y-96097D01*
G01Y-98430D02*
X325884Y-97263D01*
X326976Y-96388D01*
X328504Y-96097D01*
X329595Y-96388D01*
X330906Y-97263D01*
G01X342074Y-105722D02*
X343166Y-106888D01*
X344694Y-107763D01*
X346004D01*
X347314Y-107180D01*
X348187Y-106305D01*
X348624Y-105139D01*
X348406Y-103388D01*
X347532Y-102513D01*
X343602Y-100763D01*
X342729Y-98721D01*
X343166Y-97263D01*
X344039Y-96388D01*
X345349Y-96097D01*
X346659Y-96388D01*
X347969Y-97263D01*
G01X340966Y-135263D02*
Y-152763D01*
X332232D01*
G01X323902Y-149263D02*
X322593Y-151305D01*
X320846Y-152471D01*
X318881Y-152763D01*
X317134Y-152471D01*
X315387Y-151013D01*
X314296Y-149263D01*
X314077Y-147513D01*
X314514Y-145472D01*
X316042Y-144013D01*
X317571Y-143430D01*
X319536D01*
G01X317571D02*
X316261Y-142555D01*
X315169Y-141097D01*
X314732Y-139347D01*
X315169Y-137596D01*
X316261Y-136138D01*
X318226Y-135263D01*
X320191Y-135555D01*
X322156Y-136722D01*
G01X307058Y-135263D02*
X301599Y-152763D01*
X296140Y-135263D01*
G01X279296Y-136722D02*
X280606Y-135846D01*
X282134Y-135263D01*
X283881D01*
X285846Y-136138D01*
X287374Y-137596D01*
X288466Y-139347D01*
X289339Y-142263D01*
X289558Y-144888D01*
X289121Y-147513D01*
X288466Y-149263D01*
X287156Y-151013D01*
X285627Y-152180D01*
X284099Y-152763D01*
X282571D01*
X281042Y-152180D01*
X279732Y-151305D01*
X278640Y-150139D01*
G01X261796Y-136722D02*
X263106Y-135846D01*
X264634Y-135263D01*
X266381D01*
X268346Y-136138D01*
X269874Y-137596D01*
X270966Y-139347D01*
X271839Y-142263D01*
X272058Y-144888D01*
X271621Y-147513D01*
X270966Y-149263D01*
X269656Y-151013D01*
X268127Y-152180D01*
X266599Y-152763D01*
X265071D01*
X263542Y-152180D01*
X262232Y-151305D01*
X261140Y-150139D01*
G01X404346Y-107763D02*
Y-90263D01*
X408712D01*
X410459Y-91138D01*
X411769Y-92305D01*
X412861Y-94054D01*
X413734Y-96097D01*
X413952Y-99013D01*
X413734Y-101930D01*
X412861Y-103972D01*
X411769Y-105722D01*
X410459Y-106888D01*
X408712Y-107763D01*
X404346D01*
G01X423374Y-99888D02*
X430361D01*
X429706Y-97846D01*
X428614Y-96680D01*
X427086Y-96097D01*
X425557Y-96388D01*
X424247Y-97263D01*
X423374Y-99305D01*
X422937Y-101055D01*
Y-102805D01*
X423374Y-104555D01*
X424466Y-106305D01*
X425776Y-107471D01*
X427304Y-107763D01*
X428832Y-107180D01*
X430361Y-105430D01*
G01X440874Y-105722D02*
X441966Y-106888D01*
X443494Y-107763D01*
X444804D01*
X446114Y-107180D01*
X446987Y-106305D01*
X447424Y-105139D01*
X447206Y-103388D01*
X446332Y-102513D01*
X442402Y-100763D01*
X441529Y-98721D01*
X441966Y-97263D01*
X442839Y-96388D01*
X444149Y-96097D01*
X445459Y-96388D01*
X446769Y-97263D01*
G01X461649Y-96097D02*
Y-107763D01*
G01Y-91430D02*
X461212Y-91138D01*
Y-90555D01*
X461649Y-90263D01*
X462086Y-90555D01*
Y-91138D01*
X461649Y-91430D01*
G01X476092Y-112138D02*
X477621Y-113305D01*
X479367Y-113596D01*
X480895Y-113305D01*
X482206Y-111847D01*
X483079Y-109805D01*
Y-96097D01*
G01Y-98430D02*
X482206Y-97263D01*
X480895Y-96388D01*
X479367Y-96097D01*
X477621Y-96680D01*
X476529Y-97846D01*
X475655Y-99888D01*
X475219Y-101930D01*
X475437Y-103680D01*
X476311Y-105722D01*
X477621Y-107180D01*
X479367Y-107763D01*
X480677Y-107471D01*
X482206Y-106305D01*
X483079Y-105139D01*
G01X492937Y-107763D02*
Y-96097D01*
G01Y-99013D02*
X493811Y-97555D01*
X495121Y-96388D01*
X496867Y-96097D01*
X498395Y-96388D01*
X499706Y-97555D01*
X500361Y-99596D01*
Y-107763D01*
G01X510874Y-99888D02*
X517861D01*
X517206Y-97846D01*
X516114Y-96680D01*
X514586Y-96097D01*
X513057Y-96388D01*
X511747Y-97263D01*
X510874Y-99305D01*
X510437Y-101055D01*
Y-102805D01*
X510874Y-104555D01*
X511966Y-106305D01*
X513276Y-107471D01*
X514804Y-107763D01*
X516332Y-107180D01*
X517861Y-105430D01*
G01X528592Y-107763D02*
Y-96097D01*
G01Y-98430D02*
X529684Y-97263D01*
X530776Y-96388D01*
X532304Y-96097D01*
X533395Y-96388D01*
X534706Y-97263D01*
G01X429722Y-152763D02*
Y-135263D01*
X435399Y-149846D01*
X441076Y-135263D01*
Y-152763D01*
G01X452899D02*
X451152Y-152471D01*
X449624Y-151305D01*
X448314Y-149555D01*
X447440Y-147513D01*
X447004Y-145180D01*
Y-142846D01*
X447440Y-140513D01*
X448314Y-138471D01*
X449624Y-136722D01*
X451152Y-135555D01*
X452899Y-135263D01*
X454645Y-135555D01*
X456174Y-136722D01*
X457484Y-138471D01*
X458358Y-140513D01*
X458794Y-142846D01*
Y-145180D01*
X458358Y-147513D01*
X457484Y-149555D01*
X456174Y-151305D01*
X454645Y-152471D01*
X452899Y-152763D01*
G01X465814Y-150430D02*
X467561Y-151888D01*
X469526Y-152763D01*
X471272D01*
X473019Y-151888D01*
X474329Y-150430D01*
X474984Y-148388D01*
X474547Y-146347D01*
X473456Y-144596D01*
X471491Y-143430D01*
X468871Y-142846D01*
X467342Y-141680D01*
X466687Y-139638D01*
X467124Y-137596D01*
X468216Y-136138D01*
X469744Y-135263D01*
X471272D01*
X472801Y-135846D01*
X474111Y-137305D01*
G01X483314Y-150430D02*
X485061Y-151888D01*
X487026Y-152763D01*
X488772D01*
X490519Y-151888D01*
X491829Y-150430D01*
X492484Y-148388D01*
X492047Y-146347D01*
X490956Y-144596D01*
X488991Y-143430D01*
X486371Y-142846D01*
X484842Y-141680D01*
X484187Y-139638D01*
X484624Y-137596D01*
X485716Y-136138D01*
X487244Y-135263D01*
X488772D01*
X490301Y-135846D01*
X491611Y-137305D01*
G01X509766Y-152763D02*
X501032D01*
Y-135263D01*
X509766D01*
G01X506272Y-143721D02*
X501032D01*
G01X575349Y-152763D02*
Y-135263D01*
X572729Y-138763D01*
G01Y-152763D02*
X577969D01*
G01X588701Y-138180D02*
X590011Y-136430D01*
X591539Y-135555D01*
X593286Y-135263D01*
X595469Y-135846D01*
X596997Y-137305D01*
X597434Y-139054D01*
X597216Y-140805D01*
X596342Y-142263D01*
X591976Y-145180D01*
X590011Y-147221D01*
X588701Y-150139D01*
X588264Y-152763D01*
X597434D01*
G01X606419Y-153346D02*
X614279Y-135263D01*
G01X627849Y-152763D02*
Y-135263D01*
X625229Y-138763D01*
G01Y-152763D02*
X630469D01*
G01X645349D02*
Y-135263D01*
X642729Y-138763D01*
G01Y-152763D02*
X647969D01*
G01X658919Y-153346D02*
X666779Y-135263D01*
G01X676201Y-138180D02*
X677511Y-136430D01*
X679039Y-135555D01*
X680786Y-135263D01*
X682969Y-135846D01*
X684497Y-137305D01*
X684934Y-139054D01*
X684716Y-140805D01*
X683842Y-142263D01*
X679476Y-145180D01*
X677511Y-147221D01*
X676201Y-150139D01*
X675764Y-152763D01*
X684934D01*
G01X697849Y-135263D02*
X696102Y-135846D01*
X694792Y-137305D01*
X693919Y-139054D01*
X693264Y-141388D01*
X693046Y-144013D01*
X693264Y-146638D01*
X693919Y-148972D01*
X694792Y-150722D01*
X696102Y-152180D01*
X697849Y-152763D01*
X699595Y-152180D01*
X700906Y-150722D01*
X701779Y-148972D01*
X702434Y-146638D01*
X702652Y-144013D01*
X702434Y-141388D01*
X701779Y-139054D01*
X700906Y-137305D01*
X699595Y-135846D01*
X697849Y-135263D01*
G01X715349Y-152763D02*
Y-135263D01*
X712729Y-138763D01*
G01Y-152763D02*
X717969D01*
G01X728046Y-150139D02*
X729355Y-151597D01*
X730884Y-152471D01*
X732849Y-152763D01*
X734814Y-152180D01*
X736342Y-151013D01*
X737434Y-148972D01*
X737652Y-146638D01*
X737216Y-144305D01*
X736124Y-142846D01*
X734595Y-141680D01*
X733067Y-141388D01*
X731539Y-141680D01*
X729574Y-142846D01*
X730229Y-135263D01*
X736124D01*
G01X623046Y-107763D02*
Y-90263D01*
X627412D01*
X629159Y-91138D01*
X630469Y-92305D01*
X631561Y-94054D01*
X632434Y-96097D01*
X632652Y-99013D01*
X632434Y-101930D01*
X631561Y-103972D01*
X630469Y-105722D01*
X629159Y-106888D01*
X627412Y-107763D01*
X623046D01*
G01X649279D02*
Y-96097D01*
G01Y-98138D02*
X648406Y-96972D01*
X647095Y-96388D01*
X645567Y-96097D01*
X644039Y-96680D01*
X642729Y-97846D01*
X641855Y-99596D01*
X641419Y-101930D01*
X641855Y-104263D01*
X642729Y-106013D01*
X644039Y-107180D01*
X645567Y-107763D01*
X647095Y-107471D01*
X648406Y-106597D01*
X649279Y-105430D01*
G01X662849Y-90263D02*
Y-107763D01*
G01X659792Y-96097D02*
X665906D01*
G01X677074Y-99888D02*
X684061D01*
X683406Y-97846D01*
X682314Y-96680D01*
X680786Y-96097D01*
X679257Y-96388D01*
X677947Y-97263D01*
X677074Y-99305D01*
X676637Y-101055D01*
Y-102805D01*
X677074Y-104555D01*
X678166Y-106305D01*
X679476Y-107471D01*
X681004Y-107763D01*
X682532Y-107180D01*
X684061Y-105430D01*
M02*
